FILE_TYPE = MACRO_DRAWING;
SET COLOR_WIRE YELLOW;
SET COLOR_PROP ORANGE;
SET COLOR_DOT WHITE;
SET COLOR_ARC YELLOW;
SET COLOR_BODY GREEN;
SET COLOR_NOTE PURPLE;
SET PROP_DISPLAY VALUE;
SET PAGE_NUMBER P54;
FORCEADD UNIVERSAL_POWER..1
(-150 6225);
FORCEPROP 3 LASTPIN (-150 6175) SIG_NAME PVDD18_S5_P1\g
J 0
(-140 6185);
DISPLAY 0.659574 (-140 6185);
PAINT MONO (-140 6185);
DISPLAY INVISIBLE (-140 6185);
FORCEPROP 1 LAST HDL_POWER PVDD18_S5_P1
J 1
(-150 6275);
DISPLAY 0.489362 (-150 6275);
PAINT GREEN (-150 6275);
FORCEPROP 2 LAST CDS_LIB pure_quanta_power
J 0
(-150 6225);
DISPLAY INVISIBLE (-150 6225);
FORCEPROP 1 LAST PATH I156
J 0
(-100 6250);
DISPLAY 0.872340 (-100 6250);
PAINT AQUA (-100 6250);
DISPLAY INVISIBLE (-100 6250);
FORCEADD OFFPAGE..2
R 2
(-1400 6075);
FORCEPROP 2 LAST $XR0 54 
J 0
(-1624 6075);
DISPLAY 0.638298 (-1624 6075);
PAINT MONO (-1624 6075);
FORCEPROP 2 LAST CDS_LIB standard
J 0
(-1400 6075);
DISPLAY INVISIBLE (-1400 6075);
FORCEPROP 1 LAST OFFPAGE TRUE
J 2
(-1725 5950);
DISPLAY 0.872340 (-1725 5950);
PAINT GREEN (-1725 5950);
DISPLAY INVISIBLE (-1725 5950);
FORCEPROP 1 LAST COMMENT_BODY TRUE
J 2
(-1355 5980);
DISPLAY 0.872340 (-1355 5980);
PAINT PEACH (-1355 5980);
DISPLAY INVISIBLE (-1355 5980);
FORCEPROP 2 LAST PATH I162
J 0
(-1350 6150);
DISPLAY 1.021277 (-1350 6150);
DISPLAY INVISIBLE (-1350 6150);
FORCEADD OFFPAGE..2
R 2
(-1400 6025);
FORCEPROP 2 LAST $XR0 54 
J 0
(-1624 6025);
DISPLAY 0.638298 (-1624 6025);
PAINT MONO (-1624 6025);
FORCEPROP 2 LAST CDS_LIB standard
J 0
(-1400 6025);
DISPLAY INVISIBLE (-1400 6025);
FORCEPROP 1 LAST OFFPAGE TRUE
J 2
(-1725 5900);
DISPLAY 0.872340 (-1725 5900);
PAINT GREEN (-1725 5900);
DISPLAY INVISIBLE (-1725 5900);
FORCEPROP 1 LAST COMMENT_BODY TRUE
J 2
(-1355 5930);
DISPLAY 0.872340 (-1355 5930);
PAINT PEACH (-1355 5930);
DISPLAY INVISIBLE (-1355 5930);
FORCEPROP 2 LAST PATH I163
J 0
(-1350 6100);
DISPLAY 1.021277 (-1350 6100);
DISPLAY INVISIBLE (-1350 6100);
FORCEADD OFFPAGE..2
R 2
(-1400 5975);
FORCEPROP 2 LAST $XR0 54 
J 0
(-1624 5975);
DISPLAY 0.638298 (-1624 5975);
PAINT MONO (-1624 5975);
FORCEPROP 2 LAST CDS_LIB standard
J 0
(-1400 5975);
DISPLAY INVISIBLE (-1400 5975);
FORCEPROP 1 LAST OFFPAGE TRUE
J 2
(-1725 5850);
DISPLAY 0.872340 (-1725 5850);
PAINT GREEN (-1725 5850);
DISPLAY INVISIBLE (-1725 5850);
FORCEPROP 1 LAST COMMENT_BODY TRUE
J 2
(-1355 5880);
DISPLAY 0.872340 (-1355 5880);
PAINT PEACH (-1355 5880);
DISPLAY INVISIBLE (-1355 5880);
FORCEPROP 2 LAST PATH I164
J 0
(-1350 6050);
DISPLAY 1.021277 (-1350 6050);
DISPLAY INVISIBLE (-1350 6050);
FORCEADD OFFPAGE..2
R 2
(-1400 5925);
FORCEPROP 2 LAST $XR0 54 
J 0
(-1624 5925);
DISPLAY 0.638298 (-1624 5925);
PAINT MONO (-1624 5925);
FORCEPROP 2 LAST CDS_LIB standard
J 0
(-1400 5925);
DISPLAY INVISIBLE (-1400 5925);
FORCEPROP 1 LAST OFFPAGE TRUE
J 2
(-1725 5800);
DISPLAY 0.872340 (-1725 5800);
PAINT GREEN (-1725 5800);
DISPLAY INVISIBLE (-1725 5800);
FORCEPROP 1 LAST COMMENT_BODY TRUE
J 2
(-1355 5830);
DISPLAY 0.872340 (-1355 5830);
PAINT PEACH (-1355 5830);
DISPLAY INVISIBLE (-1355 5830);
FORCEPROP 2 LAST PATH I165
J 0
(-1350 6000);
DISPLAY 1.021277 (-1350 6000);
DISPLAY INVISIBLE (-1350 6000);
FORCEADD OFFPAGE..2
R 2
(-1400 5875);
FORCEPROP 2 LAST $XR0 54 
J 0
(-1624 5875);
DISPLAY 0.638298 (-1624 5875);
PAINT MONO (-1624 5875);
FORCEPROP 2 LAST CDS_LIB standard
J 0
(-1400 5875);
DISPLAY INVISIBLE (-1400 5875);
FORCEPROP 1 LAST OFFPAGE TRUE
J 2
(-1725 5750);
DISPLAY 0.872340 (-1725 5750);
PAINT GREEN (-1725 5750);
DISPLAY INVISIBLE (-1725 5750);
FORCEPROP 1 LAST COMMENT_BODY TRUE
J 2
(-1355 5780);
DISPLAY 0.872340 (-1355 5780);
PAINT PEACH (-1355 5780);
DISPLAY INVISIBLE (-1355 5780);
FORCEPROP 2 LAST PATH I166
J 0
(-1350 5950);
DISPLAY 1.021277 (-1350 5950);
DISPLAY INVISIBLE (-1350 5950);
FORCEADD OFFPAGE..2
R 2
(-1400 5825);
FORCEPROP 2 LAST $XR0 54 
J 0
(-1624 5825);
DISPLAY 0.638298 (-1624 5825);
PAINT MONO (-1624 5825);
FORCEPROP 2 LAST CDS_LIB standard
J 0
(-1400 5825);
DISPLAY INVISIBLE (-1400 5825);
FORCEPROP 1 LAST OFFPAGE TRUE
J 2
(-1725 5700);
DISPLAY 0.872340 (-1725 5700);
PAINT GREEN (-1725 5700);
DISPLAY INVISIBLE (-1725 5700);
FORCEPROP 1 LAST COMMENT_BODY TRUE
J 2
(-1355 5730);
DISPLAY 0.872340 (-1355 5730);
PAINT PEACH (-1355 5730);
DISPLAY INVISIBLE (-1355 5730);
FORCEPROP 2 LAST PATH I168
J 0
(-1350 5900);
DISPLAY 1.021277 (-1350 5900);
DISPLAY INVISIBLE (-1350 5900);
FORCEADD OFFPAGE..2
R 2
(-1400 5775);
FORCEPROP 2 LAST $XR2 82 
J 0
(-1804 5775);
DISPLAY 0.638298 (-1804 5775);
PAINT MONO (-1804 5775);
FORCEPROP 2 LAST $XR1 54 
J 0
(-1714 5775);
DISPLAY 0.638298 (-1714 5775);
PAINT MONO (-1714 5775);
FORCEPROP 2 LAST $XR0 27 
J 0
(-1624 5775);
DISPLAY 0.638298 (-1624 5775);
PAINT MONO (-1624 5775);
FORCEPROP 2 LAST CDS_LIB standard
J 0
(-1400 5775);
DISPLAY INVISIBLE (-1400 5775);
FORCEPROP 1 LAST OFFPAGE TRUE
J 2
(-1725 5650);
DISPLAY 0.872340 (-1725 5650);
PAINT GREEN (-1725 5650);
DISPLAY INVISIBLE (-1725 5650);
FORCEPROP 1 LAST COMMENT_BODY TRUE
J 2
(-1355 5680);
DISPLAY 0.872340 (-1355 5680);
PAINT PEACH (-1355 5680);
DISPLAY INVISIBLE (-1355 5680);
FORCEPROP 2 LAST PATH I176
J 0
(-1350 5850);
DISPLAY 1.021277 (-1350 5850);
DISPLAY INVISIBLE (-1350 5850);
FORCEADD OFFPAGE..2
R 2
(-1400 5725);
FORCEPROP 2 LAST $XR2 82 
J 0
(-1804 5725);
DISPLAY 0.638298 (-1804 5725);
PAINT MONO (-1804 5725);
FORCEPROP 2 LAST $XR1 54 
J 0
(-1714 5725);
DISPLAY 0.638298 (-1714 5725);
PAINT MONO (-1714 5725);
FORCEPROP 2 LAST $XR0 27 
J 0
(-1624 5725);
DISPLAY 0.638298 (-1624 5725);
PAINT MONO (-1624 5725);
FORCEPROP 2 LAST CDS_LIB standard
J 0
(-1400 5725);
DISPLAY INVISIBLE (-1400 5725);
FORCEPROP 1 LAST OFFPAGE TRUE
J 2
(-1725 5600);
DISPLAY 0.872340 (-1725 5600);
PAINT GREEN (-1725 5600);
DISPLAY INVISIBLE (-1725 5600);
FORCEPROP 1 LAST COMMENT_BODY TRUE
J 2
(-1355 5630);
DISPLAY 0.872340 (-1355 5630);
PAINT PEACH (-1355 5630);
DISPLAY INVISIBLE (-1355 5630);
FORCEPROP 2 LAST PATH I177
J 0
(-1350 5800);
DISPLAY 1.021277 (-1350 5800);
DISPLAY INVISIBLE (-1350 5800);
FORCEADD OFFPAGE..2
R 2
(-1400 5675);
FORCEPROP 2 LAST $XR2 82 
J 0
(-1804 5675);
DISPLAY 0.638298 (-1804 5675);
PAINT MONO (-1804 5675);
FORCEPROP 2 LAST $XR1 54 
J 0
(-1714 5675);
DISPLAY 0.638298 (-1714 5675);
PAINT MONO (-1714 5675);
FORCEPROP 2 LAST $XR0 27 
J 0
(-1624 5675);
DISPLAY 0.638298 (-1624 5675);
PAINT MONO (-1624 5675);
FORCEPROP 2 LAST CDS_LIB standard
J 0
(-1400 5675);
DISPLAY INVISIBLE (-1400 5675);
FORCEPROP 1 LAST OFFPAGE TRUE
J 2
(-1725 5550);
DISPLAY 0.872340 (-1725 5550);
PAINT GREEN (-1725 5550);
DISPLAY INVISIBLE (-1725 5550);
FORCEPROP 1 LAST COMMENT_BODY TRUE
J 2
(-1355 5580);
DISPLAY 0.872340 (-1355 5580);
PAINT PEACH (-1355 5580);
DISPLAY INVISIBLE (-1355 5580);
FORCEPROP 2 LAST PATH I178
J 0
(-1350 5750);
DISPLAY 1.021277 (-1350 5750);
DISPLAY INVISIBLE (-1350 5750);
FORCEADD OFFPAGE..2
R 2
(-1400 5625);
FORCEPROP 2 LAST $XR2 82 
J 0
(-1804 5625);
DISPLAY 0.638298 (-1804 5625);
PAINT MONO (-1804 5625);
FORCEPROP 2 LAST $XR1 54 
J 0
(-1714 5625);
DISPLAY 0.638298 (-1714 5625);
PAINT MONO (-1714 5625);
FORCEPROP 2 LAST $XR0 27 
J 0
(-1624 5625);
DISPLAY 0.638298 (-1624 5625);
PAINT MONO (-1624 5625);
FORCEPROP 2 LAST CDS_LIB standard
J 0
(-1400 5625);
DISPLAY INVISIBLE (-1400 5625);
FORCEPROP 1 LAST OFFPAGE TRUE
J 2
(-1725 5500);
DISPLAY 0.872340 (-1725 5500);
PAINT GREEN (-1725 5500);
DISPLAY INVISIBLE (-1725 5500);
FORCEPROP 1 LAST COMMENT_BODY TRUE
J 2
(-1355 5530);
DISPLAY 0.872340 (-1355 5530);
PAINT PEACH (-1355 5530);
DISPLAY INVISIBLE (-1355 5530);
FORCEPROP 2 LAST PATH I179
J 0
(-1350 5700);
DISPLAY 1.021277 (-1350 5700);
DISPLAY INVISIBLE (-1350 5700);
FORCEADD GENOA_SP5..20
(-4650 3750);
FORCEPROP 1 LAST LOCATION U26
J 0
(-5250 6350);
DISPLAY 0.489362 (-5250 6350);
PAINT SKYBLUE (-5250 6350);
FORCEPROP 0 LAST $SEC 20
J 0
(-5225 6525);
DISPLAY 0.680851 (-5225 6525);
PAINT MONO (-5225 6525);
DISPLAY INVISIBLE (-5225 6525);
FORCEPROP 0 LAST CDS_SEC 20
J 0
(-5200 6250);
DISPLAY 1.021277 (-5200 6250);
DISPLAY INVISIBLE (-5200 6250);
FORCEPROP 0 LASTPIN (-3900 5125) $PN A68
J 0
(-3890 5135);
DISPLAY 0.489362 (-3890 5135);
PAINT MONO (-3890 5135);
FORCEPROP 0 LASTPIN (-3900 6025) $PN C32
J 0
(-3890 6035);
DISPLAY 0.489362 (-3890 6035);
PAINT MONO (-3890 6035);
FORCEPROP 0 LASTPIN (-3900 5975) $PN A34
J 0
(-3890 5985);
DISPLAY 0.489362 (-3890 5985);
PAINT MONO (-3890 5985);
FORCEPROP 0 LASTPIN (-3900 5925) $PN C33
J 0
(-3890 5935);
DISPLAY 0.489362 (-3890 5935);
PAINT MONO (-3890 5935);
FORCEPROP 0 LASTPIN (-3900 5875) $PN D33
J 0
(-3890 5885);
DISPLAY 0.489362 (-3890 5885);
PAINT MONO (-3890 5885);
FORCEPROP 0 LASTPIN (-3900 5825) $PN A33
J 0
(-3890 5835);
DISPLAY 0.489362 (-3890 5835);
PAINT MONO (-3890 5835);
FORCEPROP 0 LASTPIN (-3900 5775) $PN A32
J 0
(-3890 5785);
DISPLAY 0.489362 (-3890 5785);
PAINT MONO (-3890 5785);
FORCEPROP 0 LASTPIN (-3900 5725) $PN D32
J 0
(-3890 5735);
DISPLAY 0.489362 (-3890 5735);
PAINT MONO (-3890 5735);
FORCEPROP 0 LASTPIN (-3900 4475) $PN C63
J 0
(-3890 4485);
DISPLAY 0.489362 (-3890 4485);
PAINT MONO (-3890 4485);
FORCEPROP 0 LASTPIN (-3900 4425) $PN C62
J 0
(-3890 4435);
DISPLAY 0.489362 (-3890 4435);
PAINT MONO (-3890 4435);
FORCEPROP 0 LASTPIN (-3900 4375) $PN A63
J 0
(-3890 4385);
DISPLAY 0.489362 (-3890 4385);
PAINT MONO (-3890 4385);
FORCEPROP 0 LASTPIN (-3900 4325) $PN A62
J 0
(-3890 4335);
DISPLAY 0.489362 (-3890 4335);
PAINT MONO (-3890 4335);
FORCEPROP 0 LASTPIN (-5400 2775) $PN C70
J 2
(-5410 2785);
DISPLAY 0.489362 (-5410 2785);
PAINT MONO (-5410 2785);
FORCEPROP 0 LASTPIN (-5400 2725) $PN B69
J 2
(-5410 2735);
DISPLAY 0.489362 (-5410 2735);
PAINT MONO (-5410 2735);
FORCEPROP 0 LASTPIN (-5400 2675) $PN D68
J 2
(-5410 2685);
DISPLAY 0.489362 (-5410 2685);
PAINT MONO (-5410 2685);
FORCEPROP 0 LASTPIN (-5400 3325) $PN B66
J 2
(-5410 3335);
DISPLAY 0.489362 (-5410 3335);
PAINT MONO (-5410 3335);
FORCEPROP 0 LASTPIN (-5400 4525) $PN C16
J 2
(-5410 4535);
DISPLAY 0.489362 (-5410 4535);
PAINT MONO (-5410 4535);
FORCEPROP 0 LASTPIN (-5400 5925) $PN C22
J 2
(-5410 5935);
DISPLAY 0.489362 (-5410 5935);
PAINT MONO (-5410 5935);
FORCEPROP 0 LASTPIN (-5400 5875) $PN DG72
J 2
(-5410 5885);
DISPLAY 0.489362 (-5410 5885);
PAINT MONO (-5410 5885);
FORCEPROP 0 LASTPIN (-3900 5025) $PN A69
J 0
(-3890 5035);
DISPLAY 0.489362 (-3890 5035);
PAINT MONO (-3890 5035);
FORCEPROP 0 LASTPIN (-5400 1375) $PN DH8
J 2
(-5410 1385);
DISPLAY 0.489362 (-5410 1385);
PAINT MONO (-5410 1385);
FORCEPROP 0 LASTPIN (-5400 3225) $PN DJ55
J 2
(-5410 3235);
DISPLAY 0.489362 (-5410 3235);
PAINT MONO (-5410 3235);
FORCEPROP 0 LASTPIN (-5400 3175) $PN DJ56
J 2
(-5410 3185);
DISPLAY 0.489362 (-5410 3185);
PAINT MONO (-5410 3185);
FORCEPROP 0 LASTPIN (-5400 5125) $PN DJ71
J 2
(-5410 5135);
DISPLAY 0.489362 (-5410 5135);
PAINT MONO (-5410 5135);
FORCEPROP 0 LASTPIN (-5400 5075) $PN DH71
J 2
(-5410 5085);
DISPLAY 0.489362 (-5410 5085);
PAINT MONO (-5410 5085);
FORCEPROP 0 LASTPIN (-5400 3025) $PN C19
J 2
(-5410 3035);
DISPLAY 0.489362 (-5410 3035);
PAINT MONO (-5410 3035);
FORCEPROP 0 LASTPIN (-5400 2975) $PN C68
J 2
(-5410 2985);
DISPLAY 0.489362 (-5410 2985);
PAINT MONO (-5410 2985);
FORCEPROP 0 LASTPIN (-5400 2925) $PN DH73
J 2
(-5410 2935);
DISPLAY 0.489362 (-5410 2935);
PAINT MONO (-5410 2935);
FORCEPROP 0 LASTPIN (-5400 2875) $PN DH10
J 2
(-5410 2885);
DISPLAY 0.489362 (-5410 2885);
PAINT MONO (-5410 2885);
FORCEPROP 0 LASTPIN (-5400 5775) $PN A23
J 2
(-5410 5785);
DISPLAY 0.489362 (-5410 5785);
PAINT MONO (-5410 5785);
FORCEPROP 0 LASTPIN (-5400 5575) $PN DJ72
J 2
(-5410 5585);
DISPLAY 0.489362 (-5410 5585);
PAINT MONO (-5410 5585);
FORCEPROP 0 LASTPIN (-5400 5725) $PN A22
J 2
(-5410 5735);
DISPLAY 0.489362 (-5410 5735);
PAINT MONO (-5410 5735);
FORCEPROP 0 LASTPIN (-5400 5525) $PN DH72
J 2
(-5410 5535);
DISPLAY 0.489362 (-5410 5535);
PAINT MONO (-5410 5535);
FORCEPROP 0 LASTPIN (-5400 5675) $PN B21
J 2
(-5410 5685);
DISPLAY 0.489362 (-5410 5685);
PAINT MONO (-5410 5685);
FORCEPROP 0 LASTPIN (-5400 5475) $PN DG73
J 2
(-5410 5485);
DISPLAY 0.489362 (-5410 5485);
PAINT MONO (-5410 5485);
FORCEPROP 0 LASTPIN (-5400 4675) $PN B17
J 2
(-5410 4685);
DISPLAY 0.489362 (-5410 4685);
PAINT MONO (-5410 4685);
FORCEPROP 0 LASTPIN (-5400 4775) $PN C17
J 2
(-5410 4785);
DISPLAY 0.489362 (-5410 4785);
PAINT MONO (-5410 4785);
FORCEPROP 0 LASTPIN (-5400 4825) $PN C18
J 2
(-5410 4835);
DISPLAY 0.489362 (-5410 4835);
PAINT MONO (-5410 4835);
FORCEPROP 0 LASTPIN (-3900 3375) $PN AA50
J 0
(-3890 3385);
DISPLAY 0.489362 (-3890 3385);
PAINT MONO (-3890 3385);
FORCEPROP 0 LASTPIN (-3900 3325) $PN CJ28
J 0
(-3890 3335);
DISPLAY 0.489362 (-3890 3335);
PAINT MONO (-3890 3335);
FORCEPROP 0 LASTPIN (-3900 3275) $PN CJ48
J 0
(-3890 3285);
DISPLAY 0.489362 (-3890 3285);
PAINT MONO (-3890 3285);
FORCEPROP 0 LASTPIN (-3900 3225) $PN AA30
J 0
(-3890 3235);
DISPLAY 0.489362 (-3890 3235);
PAINT MONO (-3890 3235);
FORCEPROP 0 LASTPIN (-3900 3175) $PN AA52
J 0
(-3890 3185);
DISPLAY 0.489362 (-3890 3185);
PAINT MONO (-3890 3185);
FORCEPROP 0 LASTPIN (-3900 3125) $PN CJ26
J 0
(-3890 3135);
DISPLAY 0.489362 (-3890 3135);
PAINT MONO (-3890 3135);
FORCEPROP 0 LASTPIN (-3900 3075) $PN CJ50
J 0
(-3890 3085);
DISPLAY 0.489362 (-3890 3085);
PAINT MONO (-3890 3085);
FORCEPROP 0 LASTPIN (-3900 3025) $PN AA27
J 0
(-3890 3035);
DISPLAY 0.489362 (-3890 3035);
PAINT MONO (-3890 3035);
FORCEPROP 0 LASTPIN (-3900 2975) $PN AA48
J 0
(-3890 2985);
DISPLAY 0.489362 (-3890 2985);
PAINT MONO (-3890 2985);
FORCEPROP 0 LASTPIN (-3900 2925) $PN CK30
J 0
(-3890 2935);
DISPLAY 0.489362 (-3890 2935);
PAINT MONO (-3890 2935);
FORCEPROP 0 LASTPIN (-3900 2875) $PN CJ47
J 0
(-3890 2885);
DISPLAY 0.489362 (-3890 2885);
PAINT MONO (-3890 2885);
FORCEPROP 0 LASTPIN (-3900 2825) $PN AA28
J 0
(-3890 2835);
DISPLAY 0.489362 (-3890 2835);
PAINT MONO (-3890 2835);
FORCEPROP 0 LASTPIN (-3900 2075) $PN AA25
J 0
(-3890 2085);
DISPLAY 0.489362 (-3890 2085);
PAINT MONO (-3890 2085);
FORCEPROP 0 LASTPIN (-3900 2725) $PN AA51
J 0
(-3890 2735);
DISPLAY 0.489362 (-3890 2735);
PAINT MONO (-3890 2735);
FORCEPROP 0 LASTPIN (-3900 2675) $PN CJ27
J 0
(-3890 2685);
DISPLAY 0.489362 (-3890 2685);
PAINT MONO (-3890 2685);
FORCEPROP 0 LASTPIN (-3900 2625) $PN CJ49
J 0
(-3890 2635);
DISPLAY 0.489362 (-3890 2635);
PAINT MONO (-3890 2635);
FORCEPROP 0 LASTPIN (-3900 2575) $PN Y30
J 0
(-3890 2585);
DISPLAY 0.489362 (-3890 2585);
PAINT MONO (-3890 2585);
FORCEPROP 0 LASTPIN (-3900 2525) $PN AA53
J 0
(-3890 2535);
DISPLAY 0.489362 (-3890 2535);
PAINT MONO (-3890 2535);
FORCEPROP 0 LASTPIN (-3900 2475) $PN CJ25
J 0
(-3890 2485);
DISPLAY 0.489362 (-3890 2485);
PAINT MONO (-3890 2485);
FORCEPROP 0 LASTPIN (-3900 2425) $PN CJ51
J 0
(-3890 2435);
DISPLAY 0.489362 (-3890 2435);
PAINT MONO (-3890 2435);
FORCEPROP 0 LASTPIN (-3900 2375) $PN AA26
J 0
(-3890 2385);
DISPLAY 0.489362 (-3890 2385);
PAINT MONO (-3890 2385);
FORCEPROP 0 LASTPIN (-3900 2325) $PN Y47
J 0
(-3890 2335);
DISPLAY 0.489362 (-3890 2335);
PAINT MONO (-3890 2335);
FORCEPROP 0 LASTPIN (-3900 2275) $PN CK29
J 0
(-3890 2285);
DISPLAY 0.489362 (-3890 2285);
PAINT MONO (-3890 2285);
FORCEPROP 0 LASTPIN (-3900 2225) $PN CK47
J 0
(-3890 2235);
DISPLAY 0.489362 (-3890 2235);
PAINT MONO (-3890 2235);
FORCEPROP 0 LASTPIN (-3900 2175) $PN Y29
J 0
(-3890 2185);
DISPLAY 0.489362 (-3890 2185);
PAINT MONO (-3890 2185);
FORCEPROP 0 LASTPIN (-3900 1975) $PN AA24
J 0
(-3890 1985);
DISPLAY 0.489362 (-3890 1985);
PAINT MONO (-3890 1985);
FORCEPROP 0 LASTPIN (-3900 4125) $PN AA46
J 0
(-3890 4135);
DISPLAY 0.489362 (-3890 4135);
PAINT MONO (-3890 4135);
FORCEPROP 0 LASTPIN (-3900 4075) $PN CJ30
J 0
(-3890 4085);
DISPLAY 0.489362 (-3890 4085);
PAINT MONO (-3890 4085);
FORCEPROP 0 LASTPIN (-3900 4025) $PN CJ46
J 0
(-3890 4035);
DISPLAY 0.489362 (-3890 4035);
PAINT MONO (-3890 4035);
FORCEPROP 0 LASTPIN (-3900 3975) $PN Y46
J 0
(-3890 3985);
DISPLAY 0.489362 (-3890 3985);
PAINT MONO (-3890 3985);
FORCEPROP 0 LASTPIN (-3900 3475) $PN AA49
J 0
(-3890 3485);
DISPLAY 0.489362 (-3890 3485);
PAINT MONO (-3890 3485);
FORCEPROP 0 LASTPIN (-3900 3825) $PN AA47
J 0
(-3890 3835);
DISPLAY 0.489362 (-3890 3835);
PAINT MONO (-3890 3835);
FORCEPROP 0 LASTPIN (-3900 3775) $PN CJ29
J 0
(-3890 3785);
DISPLAY 0.489362 (-3890 3785);
PAINT MONO (-3890 3785);
FORCEPROP 0 LASTPIN (-3900 3725) $PN AA29
J 0
(-3890 3735);
DISPLAY 0.489362 (-3890 3735);
PAINT MONO (-3890 3735);
FORCEPROP 0 LASTPIN (-3900 3675) $PN CJ52
J 0
(-3890 3685);
DISPLAY 0.489362 (-3890 3685);
PAINT MONO (-3890 3685);
FORCEPROP 0 LASTPIN (-3900 3625) $PN AA23
J 0
(-3890 3635);
DISPLAY 0.489362 (-3890 3635);
PAINT MONO (-3890 3635);
FORCEPROP 0 LASTPIN (-3900 3575) $PN CJ53
J 0
(-3890 3585);
DISPLAY 0.489362 (-3890 3585);
PAINT MONO (-3890 3585);
FORCEPROP 0 LASTPIN (-3900 1375) $PN W31
J 0
(-3890 1385);
DISPLAY 0.489362 (-3890 1385);
PAINT MONO (-3890 1385);
FORCEPROP 0 LASTPIN (-5400 4075) $PN B60
J 2
(-5410 4085);
DISPLAY 0.489362 (-5410 4085);
PAINT MONO (-5410 4085);
FORCEPROP 0 LASTPIN (-5400 4025) $PN CJ24
J 2
(-5410 4035);
DISPLAY 0.489362 (-5410 4035);
PAINT MONO (-5410 4035);
FORCEPROP 0 LASTPIN (-5400 3975) $PN CK46
J 2
(-5410 3985);
DISPLAY 0.489362 (-5410 3985);
PAINT MONO (-5410 3985);
FORCEPROP 0 LASTPIN (-5400 3925) $PN E32
J 2
(-5410 3935);
DISPLAY 0.489362 (-5410 3935);
PAINT MONO (-5410 3935);
FORCEPROP 0 LASTPIN (-5400 3825) $PN B58
J 2
(-5410 3835);
DISPLAY 0.489362 (-5410 3835);
PAINT MONO (-5410 3835);
FORCEPROP 0 LASTPIN (-5400 3775) $PN D7
J 2
(-5410 3785);
DISPLAY 0.489362 (-5410 3785);
PAINT MONO (-5410 3785);
FORCEPROP 0 LASTPIN (-5400 3475) $PN B61
J 2
(-5410 3485);
DISPLAY 0.489362 (-5410 3485);
PAINT MONO (-5410 3485);
FORCEPROP 0 LASTPIN (-3900 4975) $PN DJ9
J 0
(-3890 4985);
DISPLAY 0.489362 (-3890 4985);
PAINT MONO (-3890 4985);
FORCEPROP 0 LASTPIN (-5400 4625) $PN A16
J 2
(-5410 4635);
DISPLAY 0.489362 (-5410 4635);
PAINT MONO (-5410 4635);
FORCEPROP 0 LASTPIN (-5400 4725) $PN A17
J 2
(-5410 4735);
DISPLAY 0.489362 (-5410 4735);
PAINT MONO (-5410 4735);
FORCEPROP 0 LASTPIN (-3900 1875) $PN DJ33
J 0
(-3890 1885);
DISPLAY 0.489362 (-3890 1885);
PAINT MONO (-3890 1885);
FORCEPROP 0 LASTPIN (-3900 1775) $PN DG34
J 0
(-3890 1785);
DISPLAY 0.489362 (-3890 1785);
PAINT MONO (-3890 1785);
FORCEPROP 0 LASTPIN (-3900 1825) $PN DF34
J 0
(-3890 1835);
DISPLAY 0.489362 (-3890 1835);
PAINT MONO (-3890 1835);
FORCEPROP 0 LASTPIN (-3900 1675) $PN DG35
J 0
(-3890 1685);
DISPLAY 0.489362 (-3890 1685);
PAINT MONO (-3890 1685);
FORCEPROP 0 LASTPIN (-3900 1725) $PN DJ34
J 0
(-3890 1735);
DISPLAY 0.489362 (-3890 1735);
PAINT MONO (-3890 1735);
FORCEPROP 0 LASTPIN (-3900 1575) $PN DH33
J 0
(-3890 1585);
DISPLAY 0.489362 (-3890 1585);
PAINT MONO (-3890 1585);
FORCEPROP 0 LASTPIN (-3900 1625) $PN DJ32
J 0
(-3890 1635);
DISPLAY 0.489362 (-3890 1635);
PAINT MONO (-3890 1635);
FORCEPROP 0 LASTPIN (-5400 2175) $PN DH3
J 2
(-5410 2185);
DISPLAY 0.489362 (-5410 2185);
PAINT MONO (-5410 2185);
FORCEPROP 0 LASTPIN (-5400 2075) $PN C74
J 2
(-5410 2085);
DISPLAY 0.489362 (-5410 2085);
PAINT MONO (-5410 2085);
FORCEPROP 0 LASTPIN (-5400 2125) $PN BP53
J 2
(-5410 2135);
DISPLAY 0.489362 (-5410 2135);
PAINT MONO (-5410 2135);
FORCEPROP 0 LASTPIN (-5400 2225) $PN C2
J 2
(-5410 2235);
DISPLAY 0.489362 (-5410 2235);
PAINT MONO (-5410 2235);
FORCEPROP 0 LASTPIN (-5400 2275) $PN DG3
J 2
(-5410 2285);
DISPLAY 0.489362 (-5410 2285);
PAINT MONO (-5410 2285);
FORCEPROP 0 LASTPIN (-5400 2025) $PN B3
J 2
(-5410 2035);
DISPLAY 0.489362 (-5410 2035);
PAINT MONO (-5410 2035);
FORCEPROP 0 LASTPIN (-5400 2325) $PN BR53
J 2
(-5410 2335);
DISPLAY 0.489362 (-5410 2335);
PAINT MONO (-5410 2335);
FORCEPROP 0 LASTPIN (-5400 2575) $PN C3
J 2
(-5410 2585);
DISPLAY 0.489362 (-5410 2585);
PAINT MONO (-5410 2585);
FORCEPROP 0 LASTPIN (-5400 2525) $PN BR54
J 2
(-5410 2535);
DISPLAY 0.489362 (-5410 2535);
PAINT MONO (-5410 2535);
FORCEPROP 0 LASTPIN (-5400 2475) $PN DJ3
J 2
(-5410 2485);
DISPLAY 0.489362 (-5410 2485);
PAINT MONO (-5410 2485);
FORCEPROP 0 LASTPIN (-5400 2425) $PN B73
J 2
(-5410 2435);
DISPLAY 0.489362 (-5410 2435);
PAINT MONO (-5410 2435);
FORCEPROP 0 LASTPIN (-3900 4825) $PN C66
J 0
(-3890 4835);
DISPLAY 0.489362 (-3890 4835);
PAINT MONO (-3890 4835);
FORCEPROP 0 LASTPIN (-3900 4775) $PN C65
J 0
(-3890 4785);
DISPLAY 0.489362 (-3890 4785);
PAINT MONO (-3890 4785);
FORCEPROP 0 LASTPIN (-3900 4725) $PN A66
J 0
(-3890 4735);
DISPLAY 0.489362 (-3890 4735);
PAINT MONO (-3890 4735);
FORCEPROP 0 LASTPIN (-3900 4675) $PN A65
J 0
(-3890 4685);
DISPLAY 0.489362 (-3890 4685);
PAINT MONO (-3890 4685);
FORCEPROP 2 LAST PART_TYPE SMLF
J 0
(-5150 6200);
DISPLAY 1.021277 (-5150 6200);
FORCEPROP 2 LAST VALUE SOCKET6096_13568-001
J 0
(-5200 6100);
DISPLAY 0.489362 (-5200 6100);
PAINT SKYBLUE (-5200 6100);
FORCEPROP 1 LAST MATERIAL IO
J 0
(-5245 6207);
DISPLAY 0.489362 (-5245 6207);
PAINT SKYBLUE (-5245 6207);
FORCEPROP 1 LAST NEEDS_NO_SIZE TRUE
J 0
(-4650 3750);
DISPLAY 0.723404 (-4650 3750);
PAINT GREEN (-4650 3750);
DISPLAY INVISIBLE (-4650 3750);
FORCEPROP 1 LAST CDS_LMAN_SYM_OUTLINE -600,2425,600,-2425
J 0
(-4650 3750);
DISPLAY 0.468085 (-4650 3750);
PAINT GREEN (-4650 3750);
DISPLAY INVISIBLE (-4650 3750);
FORCEPROP 2 LAST CDS_LIB pure_quanta
J 0
(-4650 3750);
DISPLAY INVISIBLE (-4650 3750);
FORCEPROP 1 LAST PATH I190
J 0
(-4650 3750);
DISPLAY 0.723404 (-4650 3750);
PAINT GREEN (-4650 3750);
DISPLAY INVISIBLE (-4650 3750);
FORCEPROP 1 LAST PART_NUMBER DGA^6000030
J 0
(-5250 6275);
DISPLAY 0.489362 (-5250 6275);
PAINT SKYBLUE (-5250 6275);
DISPLAY INVISIBLE (-5250 6275);
FORCEADD OFFPAGE..4
(-2375 5025);
FORCEPROP 2 LAST $XR1 82 
J 0
(-2099 5025);
DISPLAY 0.638298 (-2099 5025);
PAINT MONO (-2099 5025);
FORCEPROP 2 LAST $XR0 54 
J 0
(-2189 5025);
DISPLAY 0.638298 (-2189 5025);
PAINT MONO (-2189 5025);
FORCEPROP 2 LAST CDS_LIB standard
J 2
(-2375 5025);
DISPLAY INVISIBLE (-2375 5025);
FORCEPROP 1 LAST OFFPAGE TRUE
J 0
(-2050 4900);
DISPLAY 0.872340 (-2050 4900);
PAINT GREEN (-2050 4900);
DISPLAY INVISIBLE (-2050 4900);
FORCEPROP 1 LAST COMMENT_BODY TRUE
J 0
(-2400 4925);
DISPLAY 0.872340 (-2400 4925);
PAINT GREEN (-2400 4925);
DISPLAY INVISIBLE (-2400 4925);
FORCEPROP 2 LAST PATH I192
J 0
(-2175 5075);
DISPLAY 1.021277 (-2175 5075);
DISPLAY INVISIBLE (-2175 5075);
FORCEADD OFFPAGE..3
(-3025 4425);
FORCEPROP 2 LAST $XR0 54 
J 0
(-2811 4425);
DISPLAY 0.638298 (-2811 4425);
PAINT MONO (-2811 4425);
FORCEPROP 2 LAST CDS_LIB standard
J 0
(-3025 4425);
DISPLAY INVISIBLE (-3025 4425);
FORCEPROP 1 LAST OFFPAGE TRUE
J 0
(-2700 4300);
DISPLAY 0.872340 (-2700 4300);
PAINT GREEN (-2700 4300);
DISPLAY INVISIBLE (-2700 4300);
FORCEPROP 1 LAST COMMENT_BODY TRUE
J 0
(-3075 4325);
DISPLAY 0.872340 (-3075 4325);
PAINT GREEN (-3075 4325);
DISPLAY INVISIBLE (-3075 4325);
FORCEPROP 2 LAST PATH I198
J 0
(-2800 4475);
DISPLAY 1.021277 (-2800 4475);
DISPLAY INVISIBLE (-2800 4475);
FORCEADD OFFPAGE..3
(-3025 4475);
FORCEPROP 2 LAST $XR0 54 
J 0
(-2811 4475);
DISPLAY 0.638298 (-2811 4475);
PAINT MONO (-2811 4475);
FORCEPROP 2 LAST CDS_LIB standard
J 0
(-3025 4475);
DISPLAY INVISIBLE (-3025 4475);
FORCEPROP 1 LAST OFFPAGE TRUE
J 0
(-2700 4350);
DISPLAY 0.872340 (-2700 4350);
PAINT GREEN (-2700 4350);
DISPLAY INVISIBLE (-2700 4350);
FORCEPROP 1 LAST COMMENT_BODY TRUE
J 0
(-3075 4375);
DISPLAY 0.872340 (-3075 4375);
PAINT GREEN (-3075 4375);
DISPLAY INVISIBLE (-3075 4375);
FORCEPROP 2 LAST PATH I199
J 0
(-2800 4525);
DISPLAY 1.021277 (-2800 4525);
DISPLAY INVISIBLE (-2800 4525);
FORCEADD OFFPAGE..3
(-3025 4375);
FORCEPROP 2 LAST $XR0 54 
J 0
(-2811 4375);
DISPLAY 0.638298 (-2811 4375);
PAINT MONO (-2811 4375);
FORCEPROP 2 LAST CDS_LIB standard
J 0
(-3025 4375);
DISPLAY INVISIBLE (-3025 4375);
FORCEPROP 1 LAST OFFPAGE TRUE
J 0
(-2700 4250);
DISPLAY 0.872340 (-2700 4250);
PAINT GREEN (-2700 4250);
DISPLAY INVISIBLE (-2700 4250);
FORCEPROP 1 LAST COMMENT_BODY TRUE
J 0
(-3075 4275);
DISPLAY 0.872340 (-3075 4275);
PAINT GREEN (-3075 4275);
DISPLAY INVISIBLE (-3075 4275);
FORCEPROP 2 LAST PATH I200
J 0
(-2800 4425);
DISPLAY 1.021277 (-2800 4425);
DISPLAY INVISIBLE (-2800 4425);
FORCEADD OFFPAGE..3
(-3025 4325);
FORCEPROP 2 LAST $XR0 54 
J 0
(-2811 4325);
DISPLAY 0.638298 (-2811 4325);
PAINT MONO (-2811 4325);
FORCEPROP 2 LAST CDS_LIB standard
J 0
(-3025 4325);
DISPLAY INVISIBLE (-3025 4325);
FORCEPROP 1 LAST OFFPAGE TRUE
J 0
(-2700 4200);
DISPLAY 0.872340 (-2700 4200);
PAINT GREEN (-2700 4200);
DISPLAY INVISIBLE (-2700 4200);
FORCEPROP 1 LAST COMMENT_BODY TRUE
J 0
(-3075 4225);
DISPLAY 0.872340 (-3075 4225);
PAINT GREEN (-3075 4225);
DISPLAY INVISIBLE (-3075 4225);
FORCEPROP 2 LAST PATH I201
J 0
(-2800 4375);
DISPLAY 1.021277 (-2800 4375);
DISPLAY INVISIBLE (-2800 4375);
FORCEADD Q_RES..1
R 2
(-6100 4825);
FORCEPROP 1 LAST LOCATION R529
J 2
(-6200 4825);
DISPLAY 0.489362 (-6200 4825);
PAINT SKYBLUE (-6200 4825);
FORCEPROP 0 LAST $SEC 1
J 0
(-6200 4875);
DISPLAY 0.680851 (-6200 4875);
PAINT MONO (-6200 4875);
DISPLAY INVISIBLE (-6200 4875);
FORCEPROP 0 LAST CDS_SEC 1
J 0
(-6200 4875);
DISPLAY 1.021277 (-6200 4875);
DISPLAY INVISIBLE (-6200 4875);
FORCEPROP 1 LASTPIN (-6000 4825) $PN 1
J 2
(-6012 4837);
DISPLAY 0.489362 (-6012 4837);
PAINT MONO (-6012 4837);
FORCEPROP 1 LASTPIN (-6200 4825) $PN 2
J 2
(-6162 4837);
DISPLAY 0.489362 (-6162 4837);
PAINT MONO (-6162 4837);
FORCEPROP 1 LAST VALUE 0
J 0
(-6000 4825);
DISPLAY 0.489362 (-6000 4825);
PAINT SKYBLUE (-6000 4825);
FORCEPROP 2 LAST CDS_LIB pure_quanta
J 0
(-6100 4825);
DISPLAY INVISIBLE (-6100 4825);
FORCEPROP 1 LAST WATTAGE 1/16W
J 0
(-6500 4750);
DISPLAY 0.489362 (-6500 4750);
PAINT SKYBLUE (-6500 4750);
DISPLAY INVISIBLE (-6500 4750);
FORCEPROP 1 LAST MATERIAL CHIP
J 2
(-6525 4750);
DISPLAY 0.489362 (-6525 4750);
PAINT SKYBLUE (-6525 4750);
DISPLAY INVISIBLE (-6525 4750);
FORCEPROP 1 LAST TOLERANCE 5%
J 2
(-6075 4750);
DISPLAY 0.489362 (-6075 4750);
PAINT SKYBLUE (-6075 4750);
DISPLAY INVISIBLE (-6075 4750);
FORCEPROP 1 LAST PACK_TYPE 0402LF
J 2
(-6150 4750);
DISPLAY 0.489362 (-6150 4750);
PAINT SKYBLUE (-6150 4750);
DISPLAY INVISIBLE (-6150 4750);
FORCEPROP 1 LAST PATH I203
J 2
(-6050 4975);
DISPLAY 0.978723 (-6050 4975);
PAINT WHITE (-6050 4975);
DISPLAY INVISIBLE (-6050 4975);
FORCEPROP 1 LAST PART_NUMBER CS00002JB13
J 2
(-6125 4875);
DISPLAY 0.489362 (-6125 4875);
PAINT SKYBLUE (-6125 4875);
DISPLAY INVISIBLE (-6125 4875);
FORCEADD OFFPAGE..4
R 2
(-6200 5925);
FORCEPROP 2 LAST $XR1 83 
J 0
(-6511 5925);
DISPLAY 0.638298 (-6511 5925);
PAINT MONO (-6511 5925);
FORCEPROP 2 LAST $XR0 81 
J 0
(-6421 5925);
DISPLAY 0.638298 (-6421 5925);
PAINT MONO (-6421 5925);
FORCEPROP 2 LAST CDS_LIB standard
J 0
(-6200 5925);
DISPLAY INVISIBLE (-6200 5925);
FORCEPROP 1 LAST OFFPAGE TRUE
J 2
(-6525 5800);
DISPLAY 0.872340 (-6525 5800);
PAINT GREEN (-6525 5800);
DISPLAY INVISIBLE (-6525 5800);
FORCEPROP 1 LAST COMMENT_BODY TRUE
J 2
(-6175 5825);
DISPLAY 0.872340 (-6175 5825);
PAINT GREEN (-6175 5825);
DISPLAY INVISIBLE (-6175 5825);
FORCEPROP 2 LAST PATH I204
J 0
(-6925 5975);
DISPLAY 1.021277 (-6925 5975);
DISPLAY INVISIBLE (-6925 5975);
FORCEADD OFFPAGE..4
R 2
(-6200 5875);
FORCEPROP 2 LAST $XR1 83 
J 0
(-6511 5875);
DISPLAY 0.638298 (-6511 5875);
PAINT MONO (-6511 5875);
FORCEPROP 2 LAST $XR0 81 
J 0
(-6421 5875);
DISPLAY 0.638298 (-6421 5875);
PAINT MONO (-6421 5875);
FORCEPROP 2 LAST CDS_LIB standard
J 0
(-6200 5875);
DISPLAY INVISIBLE (-6200 5875);
FORCEPROP 1 LAST OFFPAGE TRUE
J 2
(-6525 5750);
DISPLAY 0.872340 (-6525 5750);
PAINT GREEN (-6525 5750);
DISPLAY INVISIBLE (-6525 5750);
FORCEPROP 1 LAST COMMENT_BODY TRUE
J 2
(-6175 5775);
DISPLAY 0.872340 (-6175 5775);
PAINT GREEN (-6175 5775);
DISPLAY INVISIBLE (-6175 5775);
FORCEPROP 2 LAST PATH I205
J 0
(-6450 5925);
DISPLAY 1.021277 (-6450 5925);
DISPLAY INVISIBLE (-6450 5925);
FORCEADD OFFPAGE..4
R 2
(-6200 5675);
FORCEPROP 2 LAST $XR0 210 
J 0
(-6452 5675);
DISPLAY 0.638298 (-6452 5675);
PAINT MONO (-6452 5675);
FORCEPROP 2 LAST CDS_LIB standard
J 0
(-6200 5675);
DISPLAY INVISIBLE (-6200 5675);
FORCEPROP 1 LAST OFFPAGE TRUE
J 2
(-6525 5550);
DISPLAY 0.872340 (-6525 5550);
PAINT GREEN (-6525 5550);
DISPLAY INVISIBLE (-6525 5550);
FORCEPROP 1 LAST COMMENT_BODY TRUE
J 2
(-6175 5575);
DISPLAY 0.872340 (-6175 5575);
PAINT GREEN (-6175 5575);
DISPLAY INVISIBLE (-6175 5575);
FORCEPROP 2 LAST PATH I208
J 0
(-6450 5725);
DISPLAY 1.021277 (-6450 5725);
DISPLAY INVISIBLE (-6450 5725);
FORCEADD OFFPAGE..4
R 2
(-6200 5475);
FORCEPROP 2 LAST $XR0 217 
J 0
(-6452 5475);
DISPLAY 0.638298 (-6452 5475);
PAINT MONO (-6452 5475);
FORCEPROP 2 LAST CDS_LIB standard
J 0
(-6200 5475);
DISPLAY INVISIBLE (-6200 5475);
FORCEPROP 1 LAST OFFPAGE TRUE
J 2
(-6525 5350);
DISPLAY 0.872340 (-6525 5350);
PAINT GREEN (-6525 5350);
DISPLAY INVISIBLE (-6525 5350);
FORCEPROP 1 LAST COMMENT_BODY TRUE
J 2
(-6175 5375);
DISPLAY 0.872340 (-6175 5375);
PAINT GREEN (-6175 5375);
DISPLAY INVISIBLE (-6175 5375);
FORCEPROP 2 LAST PATH I211
J 0
(-6450 5525);
DISPLAY 1.021277 (-6450 5525);
DISPLAY INVISIBLE (-6450 5525);
FORCEADD OFFPAGE..4
R 2
(-6100 5125);
FORCEPROP 2 LAST $XR0 161 
J 0
(-6352 5125);
DISPLAY 0.638298 (-6352 5125);
PAINT MONO (-6352 5125);
FORCEPROP 2 LAST CDS_LIB standard
J 0
(-6100 5125);
DISPLAY INVISIBLE (-6100 5125);
FORCEPROP 1 LAST OFFPAGE TRUE
J 2
(-6425 5000);
DISPLAY 0.872340 (-6425 5000);
PAINT GREEN (-6425 5000);
DISPLAY INVISIBLE (-6425 5000);
FORCEPROP 1 LAST COMMENT_BODY TRUE
J 2
(-6075 5025);
DISPLAY 0.872340 (-6075 5025);
PAINT GREEN (-6075 5025);
DISPLAY INVISIBLE (-6075 5025);
FORCEPROP 2 LAST PATH I216
J 0
(-6375 5175);
DISPLAY 1.021277 (-6375 5175);
DISPLAY INVISIBLE (-6375 5175);
FORCEADD OFFPAGE..4
R 2
(-6100 5075);
FORCEPROP 2 LAST $XR0 161 
J 0
(-6352 5075);
DISPLAY 0.638298 (-6352 5075);
PAINT MONO (-6352 5075);
FORCEPROP 2 LAST CDS_LIB standard
J 0
(-6100 5075);
DISPLAY INVISIBLE (-6100 5075);
FORCEPROP 1 LAST OFFPAGE TRUE
J 2
(-6425 4950);
DISPLAY 0.872340 (-6425 4950);
PAINT GREEN (-6425 4950);
DISPLAY INVISIBLE (-6425 4950);
FORCEPROP 1 LAST COMMENT_BODY TRUE
J 2
(-6075 4975);
DISPLAY 0.872340 (-6075 4975);
PAINT GREEN (-6075 4975);
DISPLAY INVISIBLE (-6075 4975);
FORCEPROP 2 LAST PATH I217
J 0
(-6375 5125);
DISPLAY 1.021277 (-6375 5125);
DISPLAY INVISIBLE (-6375 5125);
FORCEADD OFFPAGE..4
R 2
(-6850 4775);
FORCEPROP 2 LAST $XR1 174 
J 0
(-7221 4775);
DISPLAY 0.638298 (-7221 4775);
PAINT MONO (-7221 4775);
FORCEPROP 2 LAST $XR0 54 
J 0
(-7101 4775);
DISPLAY 0.638298 (-7101 4775);
PAINT MONO (-7101 4775);
FORCEPROP 2 LAST CDS_LIB standard
J 0
(-6850 4775);
DISPLAY INVISIBLE (-6850 4775);
FORCEPROP 1 LAST OFFPAGE TRUE
J 2
(-7175 4650);
DISPLAY 0.872340 (-7175 4650);
PAINT GREEN (-7175 4650);
DISPLAY INVISIBLE (-7175 4650);
FORCEPROP 1 LAST COMMENT_BODY TRUE
J 2
(-6825 4675);
DISPLAY 0.872340 (-6825 4675);
PAINT GREEN (-6825 4675);
DISPLAY INVISIBLE (-6825 4675);
FORCEPROP 2 LAST PATH I219
J 0
(-7050 4825);
DISPLAY 1.021277 (-7050 4825);
DISPLAY INVISIBLE (-7050 4825);
FORCEADD OFFPAGE..2
R 2
(-6850 4825);
FORCEPROP 2 LAST $XR1 174 
J 0
(-7224 4825);
DISPLAY 0.638298 (-7224 4825);
PAINT MONO (-7224 4825);
FORCEPROP 2 LAST $XR0 54 
J 0
(-7104 4825);
DISPLAY 0.638298 (-7104 4825);
PAINT MONO (-7104 4825);
FORCEPROP 2 LAST CDS_LIB standard
J 2
(-6850 4825);
DISPLAY INVISIBLE (-6850 4825);
FORCEPROP 1 LAST OFFPAGE TRUE
J 2
(-7175 4700);
DISPLAY 0.872340 (-7175 4700);
PAINT GREEN (-7175 4700);
DISPLAY INVISIBLE (-7175 4700);
FORCEPROP 1 LAST COMMENT_BODY TRUE
J 2
(-6805 4730);
DISPLAY 0.872340 (-6805 4730);
PAINT GREEN (-6805 4730);
DISPLAY INVISIBLE (-6805 4730);
FORCEPROP 2 LAST PATH I220
J 0
(-7050 4875);
DISPLAY 1.021277 (-7050 4875);
DISPLAY INVISIBLE (-7050 4875);
FORCEADD OFFPAGE..4
R 2
(-6850 4725);
FORCEPROP 2 LAST $XR1 173 
J 0
(-7191 4725);
DISPLAY 0.638298 (-7191 4725);
PAINT MONO (-7191 4725);
FORCEPROP 2 LAST $XR0 54 
J 0
(-7071 4725);
DISPLAY 0.638298 (-7071 4725);
PAINT MONO (-7071 4725);
FORCEPROP 2 LAST CDS_LIB standard
J 2
(-6850 4725);
DISPLAY INVISIBLE (-6850 4725);
FORCEPROP 1 LAST OFFPAGE TRUE
J 2
(-7175 4600);
DISPLAY 0.872340 (-7175 4600);
PAINT GREEN (-7175 4600);
DISPLAY INVISIBLE (-7175 4600);
FORCEPROP 1 LAST COMMENT_BODY TRUE
J 2
(-6825 4625);
DISPLAY 0.872340 (-6825 4625);
PAINT GREEN (-6825 4625);
DISPLAY INVISIBLE (-6825 4625);
FORCEPROP 2 LAST PATH I221
J 0
(-7050 4775);
DISPLAY 1.021277 (-7050 4775);
DISPLAY INVISIBLE (-7050 4775);
FORCEADD OFFPAGE..4
R 2
(-6850 4675);
FORCEPROP 2 LAST $XR1 173 
J 0
(-7191 4675);
DISPLAY 0.638298 (-7191 4675);
PAINT MONO (-7191 4675);
FORCEPROP 2 LAST $XR0 54 
J 0
(-7071 4675);
DISPLAY 0.638298 (-7071 4675);
PAINT MONO (-7071 4675);
FORCEPROP 2 LAST CDS_LIB standard
J 0
(-6850 4675);
DISPLAY INVISIBLE (-6850 4675);
FORCEPROP 1 LAST OFFPAGE TRUE
J 2
(-7175 4550);
DISPLAY 0.872340 (-7175 4550);
PAINT GREEN (-7175 4550);
DISPLAY INVISIBLE (-7175 4550);
FORCEPROP 1 LAST COMMENT_BODY TRUE
J 2
(-6825 4575);
DISPLAY 0.872340 (-6825 4575);
PAINT GREEN (-6825 4575);
DISPLAY INVISIBLE (-6825 4575);
FORCEPROP 2 LAST PATH I222
J 0
(-7050 4725);
DISPLAY 1.021277 (-7050 4725);
DISPLAY INVISIBLE (-7050 4725);
FORCEADD OFFPAGE..4
R 2
(-6850 4625);
FORCEPROP 2 LAST $XR1 173 
J 0
(-7191 4625);
DISPLAY 0.638298 (-7191 4625);
PAINT MONO (-7191 4625);
FORCEPROP 2 LAST $XR0 54 
J 0
(-7071 4625);
DISPLAY 0.638298 (-7071 4625);
PAINT MONO (-7071 4625);
FORCEPROP 2 LAST CDS_LIB standard
J 0
(-6850 4625);
DISPLAY INVISIBLE (-6850 4625);
FORCEPROP 1 LAST OFFPAGE TRUE
J 2
(-7175 4500);
DISPLAY 0.872340 (-7175 4500);
PAINT GREEN (-7175 4500);
DISPLAY INVISIBLE (-7175 4500);
FORCEPROP 1 LAST COMMENT_BODY TRUE
J 2
(-6825 4525);
DISPLAY 0.872340 (-6825 4525);
PAINT GREEN (-6825 4525);
DISPLAY INVISIBLE (-6825 4525);
FORCEPROP 2 LAST PATH I224
J 0
(-7050 4675);
DISPLAY 1.021277 (-7050 4675);
DISPLAY INVISIBLE (-7050 4675);
FORCEADD OFFPAGE..4
R 2
(-6850 4525);
FORCEPROP 2 LAST $XR1 173 
J 0
(-7191 4525);
DISPLAY 0.638298 (-7191 4525);
PAINT MONO (-7191 4525);
FORCEPROP 2 LAST $XR0 54 
J 0
(-7071 4525);
DISPLAY 0.638298 (-7071 4525);
PAINT MONO (-7071 4525);
FORCEPROP 2 LAST CDS_LIB standard
J 0
(-6850 4525);
DISPLAY INVISIBLE (-6850 4525);
FORCEPROP 1 LAST OFFPAGE TRUE
J 2
(-7175 4400);
DISPLAY 0.872340 (-7175 4400);
PAINT GREEN (-7175 4400);
DISPLAY INVISIBLE (-7175 4400);
FORCEPROP 1 LAST COMMENT_BODY TRUE
J 2
(-6825 4425);
DISPLAY 0.872340 (-6825 4425);
PAINT GREEN (-6825 4425);
DISPLAY INVISIBLE (-6825 4425);
FORCEPROP 2 LAST PATH I225
J 0
(-7050 4575);
DISPLAY 1.021277 (-7050 4575);
DISPLAY INVISIBLE (-7050 4575);
FORCEADD OFFPAGE..2
(-7900 4650);
FORCEPROP 2 LAST $XR1 54 
J 0
(-7621 4650);
DISPLAY 0.638298 (-7621 4650);
PAINT MONO (-7621 4650);
FORCEPROP 2 LAST $XR0 82 
J 0
(-7711 4650);
DISPLAY 0.638298 (-7711 4650);
PAINT MONO (-7711 4650);
FORCEPROP 2 LAST CDS_LIB standard
J 0
(-7900 4650);
DISPLAY INVISIBLE (-7900 4650);
FORCEPROP 1 LAST OFFPAGE TRUE
J 0
(-7575 4525);
DISPLAY 0.872340 (-7575 4525);
PAINT GREEN (-7575 4525);
DISPLAY INVISIBLE (-7575 4525);
FORCEPROP 1 LAST COMMENT_BODY TRUE
J 0
(-7945 4555);
DISPLAY 0.872340 (-7945 4555);
PAINT PEACH (-7945 4555);
DISPLAY INVISIBLE (-7945 4555);
FORCEPROP 2 LAST PATH I235
J 0
(-7575 4700);
DISPLAY 1.021277 (-7575 4700);
DISPLAY INVISIBLE (-7575 4700);
FORCEADD OFFPAGE..2
(-7900 4600);
FORCEPROP 2 LAST $XR1 54 
J 0
(-7621 4600);
DISPLAY 0.638298 (-7621 4600);
PAINT MONO (-7621 4600);
FORCEPROP 2 LAST $XR0 82 
J 0
(-7711 4600);
DISPLAY 0.638298 (-7711 4600);
PAINT MONO (-7711 4600);
FORCEPROP 2 LAST CDS_LIB standard
J 0
(-7900 4600);
DISPLAY INVISIBLE (-7900 4600);
FORCEPROP 1 LAST OFFPAGE TRUE
J 0
(-7575 4475);
DISPLAY 0.872340 (-7575 4475);
PAINT GREEN (-7575 4475);
DISPLAY INVISIBLE (-7575 4475);
FORCEPROP 1 LAST COMMENT_BODY TRUE
J 0
(-7945 4505);
DISPLAY 0.872340 (-7945 4505);
PAINT PEACH (-7945 4505);
DISPLAY INVISIBLE (-7945 4505);
FORCEPROP 2 LAST PATH I236
J 0
(-7575 4650);
DISPLAY 1.021277 (-7575 4650);
DISPLAY INVISIBLE (-7575 4650);
FORCEADD TP..1
R 6
(-6150 1900);
FORCEPROP 1 LAST LOCATION TP20
J 1
(-6150 1802);
DISPLAY 0.489362 (-6150 1802);
PAINT SKYBLUE (-6150 1802);
FORCEPROP 0 LAST $SEC 1
J 0
(-6175 1875);
DISPLAY 0.680851 (-6175 1875);
PAINT MONO (-6175 1875);
DISPLAY INVISIBLE (-6175 1875);
FORCEPROP 0 LAST CDS_SEC 1
J 0
(-6175 1875);
DISPLAY 1.021277 (-6175 1875);
DISPLAY INVISIBLE (-6175 1875);
FORCEPROP 0 LASTPIN (-6150 1950) $PN 1
R 1
J 0
(-6160 1960);
DISPLAY 0.489362 (-6160 1960);
PAINT MONO (-6160 1960);
FORCEPROP 1 LAST MATERIAL NA
J 0
(-6175 1852);
DISPLAY 0.489362 (-6175 1852);
PAINT SKYBLUE (-6175 1852);
FORCEPROP 1 LAST PACK_TYPE TP
J 1
(-6095 1944);
DISPLAY 0.446809 (-6095 1944);
PAINT SKYBLUE (-6095 1944);
DISPLAY INVISIBLE (-6095 1944);
FORCEPROP 2 LAST CDS_LIB pure_quanta
R 3
J 2
(-6150 1853);
DISPLAY INVISIBLE (-6150 1853);
FORCEPROP 1 LASTPIN (-6150 1950) $PIN_NUMBER ?
J 2
(-6100 1917);
DISPLAY 0.702128 (-6100 1917);
PAINT MONO (-6100 1917);
DISPLAY INVISIBLE (-6100 1917);
FORCEPROP 1 LAST PATH I237
J 1
(-6145 1855);
DISPLAY 0.446809 (-6145 1855);
PAINT GREEN (-6145 1855);
DISPLAY INVISIBLE (-6145 1855);
FORCEPROP 1 LAST PART_NUMBER TP30
J 1
(-6095 1924);
DISPLAY 0.446809 (-6095 1924);
PAINT SKYBLUE (-6095 1924);
DISPLAY INVISIBLE (-6095 1924);
FORCEADD TP..1
R 6
(-6225 1900);
FORCEPROP 1 LAST LOCATION TP19
J 1
(-6225 1802);
DISPLAY 0.489362 (-6225 1802);
PAINT SKYBLUE (-6225 1802);
FORCEPROP 0 LAST $SEC 1
J 0
(-6250 1875);
DISPLAY 0.680851 (-6250 1875);
PAINT MONO (-6250 1875);
DISPLAY INVISIBLE (-6250 1875);
FORCEPROP 0 LAST CDS_SEC 1
J 0
(-6250 1875);
DISPLAY 1.021277 (-6250 1875);
DISPLAY INVISIBLE (-6250 1875);
FORCEPROP 0 LASTPIN (-6225 1950) $PN 1
R 1
J 0
(-6235 1960);
DISPLAY 0.489362 (-6235 1960);
PAINT MONO (-6235 1960);
FORCEPROP 1 LAST MATERIAL NA
J 0
(-6250 1852);
DISPLAY 0.489362 (-6250 1852);
PAINT SKYBLUE (-6250 1852);
FORCEPROP 1 LAST PACK_TYPE TP
J 1
(-6170 1944);
DISPLAY 0.446809 (-6170 1944);
PAINT SKYBLUE (-6170 1944);
DISPLAY INVISIBLE (-6170 1944);
FORCEPROP 2 LAST CDS_LIB pure_quanta
J 0
(-6225 1900);
DISPLAY INVISIBLE (-6225 1900);
FORCEPROP 1 LASTPIN (-6225 1950) $PIN_NUMBER ?
J 2
(-6175 1950);
DISPLAY 0.702128 (-6175 1950);
PAINT MONO (-6175 1950);
DISPLAY INVISIBLE (-6175 1950);
FORCEPROP 1 LAST PATH I238
J 1
(-6220 1855);
DISPLAY 0.446809 (-6220 1855);
PAINT GREEN (-6220 1855);
DISPLAY INVISIBLE (-6220 1855);
FORCEPROP 1 LAST PART_NUMBER TP30
J 1
(-6170 1924);
DISPLAY 0.446809 (-6170 1924);
PAINT SKYBLUE (-6170 1924);
DISPLAY INVISIBLE (-6170 1924);
FORCEADD UNIVERSAL_GND..1
(-5650 1225);
FORCEPROP 3 LASTPIN (-5650 1275) SIG_NAME GND\g
J 0
(-5640 1285);
DISPLAY 0.659574 (-5640 1285);
PAINT MONO (-5640 1285);
DISPLAY INVISIBLE (-5640 1285);
FORCEPROP 2 LAST CDS_LIB pure_quanta_power
J 0
(-5650 1225);
DISPLAY INVISIBLE (-5650 1225);
FORCEPROP 1 LAST HDL_POWER GND
J 1
(-5625 1150);
DISPLAY 0.872340 (-5625 1150);
PAINT GREEN (-5625 1150);
DISPLAY INVISIBLE (-5625 1150);
FORCEPROP 1 LAST PATH I239
J 0
(-5575 1225);
DISPLAY 0.872340 (-5575 1225);
PAINT AQUA (-5575 1225);
DISPLAY INVISIBLE (-5575 1225);
FORCEADD TP..1
R 6
(-6325 1900);
FORCEPROP 1 LAST LOCATION TP18
J 1
(-6325 1802);
DISPLAY 0.489362 (-6325 1802);
PAINT SKYBLUE (-6325 1802);
FORCEPROP 0 LAST $SEC 1
J 0
(-6350 1875);
DISPLAY 0.680851 (-6350 1875);
PAINT MONO (-6350 1875);
DISPLAY INVISIBLE (-6350 1875);
FORCEPROP 0 LAST CDS_SEC 1
J 0
(-6350 1875);
DISPLAY 1.021277 (-6350 1875);
DISPLAY INVISIBLE (-6350 1875);
FORCEPROP 0 LASTPIN (-6325 1950) $PN 1
R 1
J 0
(-6335 1960);
DISPLAY 0.489362 (-6335 1960);
PAINT MONO (-6335 1960);
FORCEPROP 1 LAST MATERIAL NA
J 0
(-6350 1852);
DISPLAY 0.489362 (-6350 1852);
PAINT SKYBLUE (-6350 1852);
FORCEPROP 1 LAST PACK_TYPE TP
J 1
(-6270 1944);
DISPLAY 0.446809 (-6270 1944);
PAINT SKYBLUE (-6270 1944);
DISPLAY INVISIBLE (-6270 1944);
FORCEPROP 1 LASTPIN (-6325 1950) $PIN_NUMBER ?
J 2
(-6275 1950);
DISPLAY 0.702128 (-6275 1950);
PAINT MONO (-6275 1950);
DISPLAY INVISIBLE (-6275 1950);
FORCEPROP 2 LAST CDS_LIB pure_quanta
J 0
(-6325 1900);
DISPLAY INVISIBLE (-6325 1900);
FORCEPROP 1 LAST PATH I240
J 1
(-6320 1855);
DISPLAY 0.446809 (-6320 1855);
PAINT GREEN (-6320 1855);
DISPLAY INVISIBLE (-6320 1855);
FORCEPROP 1 LAST PART_NUMBER TP30
J 1
(-6270 1924);
DISPLAY 0.446809 (-6270 1924);
PAINT SKYBLUE (-6270 1924);
DISPLAY INVISIBLE (-6270 1924);
FORCEADD TP..1
R 6
(-6400 1900);
FORCEPROP 1 LAST LOCATION TP17
J 1
(-6400 1802);
DISPLAY 0.489362 (-6400 1802);
PAINT SKYBLUE (-6400 1802);
FORCEPROP 0 LAST $SEC 1
J 0
(-6425 1875);
DISPLAY 0.680851 (-6425 1875);
PAINT MONO (-6425 1875);
DISPLAY INVISIBLE (-6425 1875);
FORCEPROP 0 LAST CDS_SEC 1
J 0
(-6425 1875);
DISPLAY 1.021277 (-6425 1875);
DISPLAY INVISIBLE (-6425 1875);
FORCEPROP 0 LASTPIN (-6400 1950) $PN 1
R 1
J 0
(-6410 1960);
DISPLAY 0.489362 (-6410 1960);
PAINT MONO (-6410 1960);
FORCEPROP 1 LAST MATERIAL NA
J 0
(-6425 1852);
DISPLAY 0.489362 (-6425 1852);
PAINT SKYBLUE (-6425 1852);
FORCEPROP 1 LAST PACK_TYPE TP
J 1
(-6345 1944);
DISPLAY 0.446809 (-6345 1944);
PAINT SKYBLUE (-6345 1944);
DISPLAY INVISIBLE (-6345 1944);
FORCEPROP 1 LASTPIN (-6400 1950) $PIN_NUMBER ?
J 2
(-6350 1950);
DISPLAY 0.702128 (-6350 1950);
PAINT MONO (-6350 1950);
DISPLAY INVISIBLE (-6350 1950);
FORCEPROP 2 LAST CDS_LIB pure_quanta
J 0
(-6400 1900);
DISPLAY INVISIBLE (-6400 1900);
FORCEPROP 1 LAST PATH I241
J 1
(-6395 1855);
DISPLAY 0.446809 (-6395 1855);
PAINT GREEN (-6395 1855);
DISPLAY INVISIBLE (-6395 1855);
FORCEPROP 1 LAST PART_NUMBER TP30
J 1
(-6345 1924);
DISPLAY 0.446809 (-6345 1924);
PAINT SKYBLUE (-6345 1924);
DISPLAY INVISIBLE (-6345 1924);
FORCEADD TP..1
R 6
(-6475 1900);
FORCEPROP 1 LAST LOCATION TP16
J 1
(-6475 1802);
DISPLAY 0.489362 (-6475 1802);
PAINT SKYBLUE (-6475 1802);
FORCEPROP 0 LAST $SEC 1
J 0
(-6500 1875);
DISPLAY 0.680851 (-6500 1875);
PAINT MONO (-6500 1875);
DISPLAY INVISIBLE (-6500 1875);
FORCEPROP 0 LAST CDS_SEC 1
J 0
(-6500 1875);
DISPLAY 1.021277 (-6500 1875);
DISPLAY INVISIBLE (-6500 1875);
FORCEPROP 0 LASTPIN (-6475 1950) $PN 1
R 1
J 0
(-6485 1960);
DISPLAY 0.489362 (-6485 1960);
PAINT MONO (-6485 1960);
FORCEPROP 1 LAST MATERIAL NA
J 0
(-6500 1852);
DISPLAY 0.489362 (-6500 1852);
PAINT SKYBLUE (-6500 1852);
FORCEPROP 1 LAST PACK_TYPE TP
J 1
(-6420 1944);
DISPLAY 0.446809 (-6420 1944);
PAINT SKYBLUE (-6420 1944);
DISPLAY INVISIBLE (-6420 1944);
FORCEPROP 2 LAST CDS_LIB pure_quanta
J 0
(-6475 1900);
DISPLAY INVISIBLE (-6475 1900);
FORCEPROP 1 LASTPIN (-6475 1950) $PIN_NUMBER ?
J 2
(-6425 1950);
DISPLAY 0.702128 (-6425 1950);
PAINT MONO (-6425 1950);
DISPLAY INVISIBLE (-6425 1950);
FORCEPROP 1 LAST PATH I242
J 1
(-6470 1855);
DISPLAY 0.446809 (-6470 1855);
PAINT GREEN (-6470 1855);
DISPLAY INVISIBLE (-6470 1855);
FORCEPROP 1 LAST PART_NUMBER TP30
J 1
(-6420 1924);
DISPLAY 0.446809 (-6420 1924);
PAINT SKYBLUE (-6420 1924);
DISPLAY INVISIBLE (-6420 1924);
FORCEADD TP..1
R 6
(-6550 1900);
FORCEPROP 1 LAST LOCATION TP15
J 1
(-6550 1802);
DISPLAY 0.489362 (-6550 1802);
PAINT SKYBLUE (-6550 1802);
FORCEPROP 0 LAST $SEC 1
J 0
(-6575 1875);
DISPLAY 0.680851 (-6575 1875);
PAINT MONO (-6575 1875);
DISPLAY INVISIBLE (-6575 1875);
FORCEPROP 0 LAST CDS_SEC 1
J 0
(-6575 1875);
DISPLAY 1.021277 (-6575 1875);
DISPLAY INVISIBLE (-6575 1875);
FORCEPROP 0 LASTPIN (-6550 1950) $PN 1
R 1
J 0
(-6560 1960);
DISPLAY 0.489362 (-6560 1960);
PAINT MONO (-6560 1960);
FORCEPROP 1 LAST MATERIAL NA
J 0
(-6575 1852);
DISPLAY 0.489362 (-6575 1852);
PAINT SKYBLUE (-6575 1852);
FORCEPROP 1 LAST PACK_TYPE TP
J 1
(-6495 1944);
DISPLAY 0.446809 (-6495 1944);
PAINT SKYBLUE (-6495 1944);
DISPLAY INVISIBLE (-6495 1944);
FORCEPROP 2 LAST CDS_LIB pure_quanta
J 0
(-6550 1900);
DISPLAY INVISIBLE (-6550 1900);
FORCEPROP 1 LASTPIN (-6550 1950) $PIN_NUMBER ?
J 2
(-6500 1950);
DISPLAY 0.702128 (-6500 1950);
PAINT MONO (-6500 1950);
DISPLAY INVISIBLE (-6500 1950);
FORCEPROP 1 LAST PATH I243
J 1
(-6545 1855);
DISPLAY 0.446809 (-6545 1855);
PAINT GREEN (-6545 1855);
DISPLAY INVISIBLE (-6545 1855);
FORCEPROP 1 LAST PART_NUMBER TP30
J 1
(-6495 1924);
DISPLAY 0.446809 (-6495 1924);
PAINT SKYBLUE (-6495 1924);
DISPLAY INVISIBLE (-6495 1924);
FORCEADD TP..1
R 6
(-6675 1900);
FORCEPROP 1 LAST LOCATION TP14
J 1
(-6675 1802);
DISPLAY 0.489362 (-6675 1802);
PAINT SKYBLUE (-6675 1802);
FORCEPROP 0 LAST $SEC 1
J 0
(-6700 1875);
DISPLAY 0.680851 (-6700 1875);
PAINT MONO (-6700 1875);
DISPLAY INVISIBLE (-6700 1875);
FORCEPROP 0 LAST CDS_SEC 1
J 0
(-6700 1875);
DISPLAY 1.021277 (-6700 1875);
DISPLAY INVISIBLE (-6700 1875);
FORCEPROP 0 LASTPIN (-6675 1950) $PN 1
R 1
J 0
(-6685 1960);
DISPLAY 0.489362 (-6685 1960);
PAINT MONO (-6685 1960);
FORCEPROP 1 LAST MATERIAL NA
J 0
(-6700 1852);
DISPLAY 0.489362 (-6700 1852);
PAINT SKYBLUE (-6700 1852);
FORCEPROP 1 LAST PACK_TYPE TP
J 1
(-6620 1944);
DISPLAY 0.446809 (-6620 1944);
PAINT SKYBLUE (-6620 1944);
DISPLAY INVISIBLE (-6620 1944);
FORCEPROP 1 LASTPIN (-6675 1950) $PIN_NUMBER ?
J 2
(-6625 1950);
DISPLAY 0.702128 (-6625 1950);
PAINT MONO (-6625 1950);
DISPLAY INVISIBLE (-6625 1950);
FORCEPROP 2 LAST CDS_LIB pure_quanta
J 0
(-6675 1900);
DISPLAY INVISIBLE (-6675 1900);
FORCEPROP 1 LAST PATH I244
J 1
(-6670 1855);
DISPLAY 0.446809 (-6670 1855);
PAINT GREEN (-6670 1855);
DISPLAY INVISIBLE (-6670 1855);
FORCEPROP 1 LAST PART_NUMBER TP30
J 1
(-6620 1924);
DISPLAY 0.446809 (-6620 1924);
PAINT SKYBLUE (-6620 1924);
DISPLAY INVISIBLE (-6620 1924);
FORCEADD TP..1
R 6
(-6750 1900);
FORCEPROP 1 LAST LOCATION TP13
J 1
(-6750 1802);
DISPLAY 0.489362 (-6750 1802);
PAINT SKYBLUE (-6750 1802);
FORCEPROP 0 LAST $SEC 1
J 0
(-6775 1875);
DISPLAY 0.680851 (-6775 1875);
PAINT MONO (-6775 1875);
DISPLAY INVISIBLE (-6775 1875);
FORCEPROP 0 LAST CDS_SEC 1
J 0
(-6775 1875);
DISPLAY 1.021277 (-6775 1875);
DISPLAY INVISIBLE (-6775 1875);
FORCEPROP 0 LASTPIN (-6750 1950) $PN 1
R 1
J 0
(-6760 1960);
DISPLAY 0.489362 (-6760 1960);
PAINT MONO (-6760 1960);
FORCEPROP 1 LAST MATERIAL NA
J 0
(-6775 1852);
DISPLAY 0.489362 (-6775 1852);
PAINT SKYBLUE (-6775 1852);
FORCEPROP 1 LAST PACK_TYPE TP
J 1
(-6695 1944);
DISPLAY 0.446809 (-6695 1944);
PAINT SKYBLUE (-6695 1944);
DISPLAY INVISIBLE (-6695 1944);
FORCEPROP 1 LASTPIN (-6750 1950) $PIN_NUMBER ?
J 2
(-6700 1950);
DISPLAY 0.702128 (-6700 1950);
PAINT MONO (-6700 1950);
DISPLAY INVISIBLE (-6700 1950);
FORCEPROP 2 LAST CDS_LIB pure_quanta
J 0
(-6750 1900);
DISPLAY INVISIBLE (-6750 1900);
FORCEPROP 1 LAST PATH I245
J 1
(-6745 1855);
DISPLAY 0.446809 (-6745 1855);
PAINT GREEN (-6745 1855);
DISPLAY INVISIBLE (-6745 1855);
FORCEPROP 1 LAST PART_NUMBER TP30
J 1
(-6695 1924);
DISPLAY 0.446809 (-6695 1924);
PAINT SKYBLUE (-6695 1924);
DISPLAY INVISIBLE (-6695 1924);
FORCEADD OFFPAGE..2
R 2
(-6650 3325);
FORCEPROP 2 LAST $XR0 167 
J 0
(-6905 3325);
DISPLAY 0.638298 (-6905 3325);
PAINT MONO (-6905 3325);
FORCEPROP 2 LAST CDS_LIB standard
J 0
(-6650 3325);
DISPLAY INVISIBLE (-6650 3325);
FORCEPROP 1 LAST OFFPAGE TRUE
J 2
(-6975 3200);
DISPLAY 0.872340 (-6975 3200);
PAINT GREEN (-6975 3200);
DISPLAY INVISIBLE (-6975 3200);
FORCEPROP 1 LAST COMMENT_BODY TRUE
J 2
(-6605 3230);
DISPLAY 0.872340 (-6605 3230);
PAINT GREEN (-6605 3230);
DISPLAY INVISIBLE (-6605 3230);
FORCEPROP 2 LAST PATH I246
J 0
(-6850 3375);
DISPLAY 1.021277 (-6850 3375);
DISPLAY INVISIBLE (-6850 3375);
FORCEADD OFFPAGE..4
R 2
(-6650 3225);
FORCEPROP 2 LAST $XR1 82 
J 0
(-6961 3225);
DISPLAY 0.638298 (-6961 3225);
PAINT MONO (-6961 3225);
FORCEPROP 2 LAST $XR0 54 
J 0
(-6871 3225);
DISPLAY 0.638298 (-6871 3225);
PAINT MONO (-6871 3225);
FORCEPROP 2 LAST CDS_LIB standard
J 0
(-6650 3225);
DISPLAY INVISIBLE (-6650 3225);
FORCEPROP 1 LAST OFFPAGE TRUE
J 2
(-6975 3100);
DISPLAY 0.872340 (-6975 3100);
PAINT GREEN (-6975 3100);
DISPLAY INVISIBLE (-6975 3100);
FORCEPROP 1 LAST COMMENT_BODY TRUE
J 2
(-6625 3125);
DISPLAY 0.872340 (-6625 3125);
PAINT GREEN (-6625 3125);
DISPLAY INVISIBLE (-6625 3125);
FORCEPROP 2 LAST PATH I247
J 0
(-6900 3275);
DISPLAY 1.021277 (-6900 3275);
DISPLAY INVISIBLE (-6900 3275);
FORCEADD OFFPAGE..4
R 2
(-6650 3175);
FORCEPROP 2 LAST $XR1 82 
J 0
(-6961 3175);
DISPLAY 0.638298 (-6961 3175);
PAINT MONO (-6961 3175);
FORCEPROP 2 LAST $XR0 54 
J 0
(-6871 3175);
DISPLAY 0.638298 (-6871 3175);
PAINT MONO (-6871 3175);
FORCEPROP 2 LAST CDS_LIB standard
J 0
(-6650 3175);
DISPLAY INVISIBLE (-6650 3175);
FORCEPROP 1 LAST OFFPAGE TRUE
J 2
(-6975 3050);
DISPLAY 0.872340 (-6975 3050);
PAINT GREEN (-6975 3050);
DISPLAY INVISIBLE (-6975 3050);
FORCEPROP 1 LAST COMMENT_BODY TRUE
J 2
(-6625 3075);
DISPLAY 0.872340 (-6625 3075);
PAINT GREEN (-6625 3075);
DISPLAY INVISIBLE (-6625 3075);
FORCEPROP 2 LAST PATH I248
J 0
(-6900 3225);
DISPLAY 1.021277 (-6900 3225);
DISPLAY INVISIBLE (-6900 3225);
FORCEADD OFFPAGE..2
R 2
(-6650 3025);
FORCEPROP 2 LAST $XR1 82 
J 0
(-6964 3025);
DISPLAY 0.638298 (-6964 3025);
PAINT MONO (-6964 3025);
FORCEPROP 2 LAST $XR0 54 
J 0
(-6874 3025);
DISPLAY 0.638298 (-6874 3025);
PAINT MONO (-6874 3025);
FORCEPROP 2 LAST CDS_LIB standard
J 0
(-6650 3025);
DISPLAY INVISIBLE (-6650 3025);
FORCEPROP 1 LAST OFFPAGE TRUE
J 2
(-6975 2900);
DISPLAY 0.872340 (-6975 2900);
PAINT GREEN (-6975 2900);
DISPLAY INVISIBLE (-6975 2900);
FORCEPROP 1 LAST COMMENT_BODY TRUE
J 2
(-6605 2930);
DISPLAY 0.872340 (-6605 2930);
PAINT GREEN (-6605 2930);
DISPLAY INVISIBLE (-6605 2930);
FORCEPROP 2 LAST PATH I249
J 0
(-6850 3075);
DISPLAY 1.021277 (-6850 3075);
DISPLAY INVISIBLE (-6850 3075);
FORCEADD OFFPAGE..2
R 2
(-6650 2975);
FORCEPROP 2 LAST $XR1 82 
J 0
(-6964 2975);
DISPLAY 0.638298 (-6964 2975);
PAINT MONO (-6964 2975);
FORCEPROP 2 LAST $XR0 54 
J 0
(-6874 2975);
DISPLAY 0.638298 (-6874 2975);
PAINT MONO (-6874 2975);
FORCEPROP 2 LAST CDS_LIB standard
J 0
(-6650 2975);
DISPLAY INVISIBLE (-6650 2975);
FORCEPROP 1 LAST OFFPAGE TRUE
J 2
(-6975 2850);
DISPLAY 0.872340 (-6975 2850);
PAINT GREEN (-6975 2850);
DISPLAY INVISIBLE (-6975 2850);
FORCEPROP 1 LAST COMMENT_BODY TRUE
J 2
(-6605 2880);
DISPLAY 0.872340 (-6605 2880);
PAINT GREEN (-6605 2880);
DISPLAY INVISIBLE (-6605 2880);
FORCEPROP 2 LAST PATH I250
J 0
(-6850 3025);
DISPLAY 1.021277 (-6850 3025);
DISPLAY INVISIBLE (-6850 3025);
FORCEADD OFFPAGE..2
R 2
(-6650 2875);
FORCEPROP 2 LAST $XR1 82 
J 0
(-6964 2875);
DISPLAY 0.638298 (-6964 2875);
PAINT MONO (-6964 2875);
FORCEPROP 2 LAST $XR0 54 
J 0
(-6874 2875);
DISPLAY 0.638298 (-6874 2875);
PAINT MONO (-6874 2875);
FORCEPROP 2 LAST CDS_LIB standard
J 0
(-6650 2875);
DISPLAY INVISIBLE (-6650 2875);
FORCEPROP 1 LAST OFFPAGE TRUE
J 2
(-6975 2750);
DISPLAY 0.872340 (-6975 2750);
PAINT GREEN (-6975 2750);
DISPLAY INVISIBLE (-6975 2750);
FORCEPROP 1 LAST COMMENT_BODY TRUE
J 2
(-6605 2780);
DISPLAY 0.872340 (-6605 2780);
PAINT GREEN (-6605 2780);
DISPLAY INVISIBLE (-6605 2780);
FORCEPROP 2 LAST PATH I251
J 0
(-6850 2925);
DISPLAY 1.021277 (-6850 2925);
DISPLAY INVISIBLE (-6850 2925);
FORCEADD OFFPAGE..2
R 2
(-6650 2925);
FORCEPROP 2 LAST $XR1 82 
J 0
(-6964 2925);
DISPLAY 0.638298 (-6964 2925);
PAINT MONO (-6964 2925);
FORCEPROP 2 LAST $XR0 54 
J 0
(-6874 2925);
DISPLAY 0.638298 (-6874 2925);
PAINT MONO (-6874 2925);
FORCEPROP 2 LAST CDS_LIB standard
J 0
(-6650 2925);
DISPLAY INVISIBLE (-6650 2925);
FORCEPROP 1 LAST OFFPAGE TRUE
J 2
(-6975 2800);
DISPLAY 0.872340 (-6975 2800);
PAINT GREEN (-6975 2800);
DISPLAY INVISIBLE (-6975 2800);
FORCEPROP 1 LAST COMMENT_BODY TRUE
J 2
(-6605 2830);
DISPLAY 0.872340 (-6605 2830);
PAINT GREEN (-6605 2830);
DISPLAY INVISIBLE (-6605 2830);
FORCEPROP 2 LAST PATH I252
J 0
(-6850 2975);
DISPLAY 1.021277 (-6850 2975);
DISPLAY INVISIBLE (-6850 2975);
FORCEADD OFFPAGE..2
R 2
(-6650 2775);
FORCEPROP 2 LAST $XR1 82 
J 0
(-6964 2775);
DISPLAY 0.638298 (-6964 2775);
PAINT MONO (-6964 2775);
FORCEPROP 2 LAST $XR0 54 
J 0
(-6874 2775);
DISPLAY 0.638298 (-6874 2775);
PAINT MONO (-6874 2775);
FORCEPROP 2 LAST CDS_LIB standard
J 0
(-6650 2775);
DISPLAY INVISIBLE (-6650 2775);
FORCEPROP 1 LAST OFFPAGE TRUE
J 2
(-6975 2650);
DISPLAY 0.872340 (-6975 2650);
PAINT GREEN (-6975 2650);
DISPLAY INVISIBLE (-6975 2650);
FORCEPROP 1 LAST COMMENT_BODY TRUE
J 2
(-6605 2680);
DISPLAY 0.872340 (-6605 2680);
PAINT GREEN (-6605 2680);
DISPLAY INVISIBLE (-6605 2680);
FORCEPROP 2 LAST PATH I253
J 0
(-6850 2825);
DISPLAY 1.021277 (-6850 2825);
DISPLAY INVISIBLE (-6850 2825);
FORCEADD OFFPAGE..2
R 2
(-6650 2725);
FORCEPROP 2 LAST $XR1 82 
J 0
(-6964 2725);
DISPLAY 0.638298 (-6964 2725);
PAINT MONO (-6964 2725);
FORCEPROP 2 LAST $XR0 54 
J 0
(-6874 2725);
DISPLAY 0.638298 (-6874 2725);
PAINT MONO (-6874 2725);
FORCEPROP 2 LAST CDS_LIB standard
J 0
(-6650 2725);
DISPLAY INVISIBLE (-6650 2725);
FORCEPROP 1 LAST OFFPAGE TRUE
J 2
(-6975 2600);
DISPLAY 0.872340 (-6975 2600);
PAINT GREEN (-6975 2600);
DISPLAY INVISIBLE (-6975 2600);
FORCEPROP 1 LAST COMMENT_BODY TRUE
J 2
(-6605 2630);
DISPLAY 0.872340 (-6605 2630);
PAINT GREEN (-6605 2630);
DISPLAY INVISIBLE (-6605 2630);
FORCEPROP 2 LAST PATH I254
J 0
(-6850 2775);
DISPLAY 1.021277 (-6850 2775);
DISPLAY INVISIBLE (-6850 2775);
FORCEADD OFFPAGE..2
R 2
(-6650 2675);
FORCEPROP 2 LAST $XR1 82 
J 0
(-6964 2675);
DISPLAY 0.638298 (-6964 2675);
PAINT MONO (-6964 2675);
FORCEPROP 2 LAST $XR0 54 
J 0
(-6874 2675);
DISPLAY 0.638298 (-6874 2675);
PAINT MONO (-6874 2675);
FORCEPROP 2 LAST CDS_LIB standard
J 0
(-6650 2675);
DISPLAY INVISIBLE (-6650 2675);
FORCEPROP 1 LAST OFFPAGE TRUE
J 2
(-6975 2550);
DISPLAY 0.872340 (-6975 2550);
PAINT GREEN (-6975 2550);
DISPLAY INVISIBLE (-6975 2550);
FORCEPROP 1 LAST COMMENT_BODY TRUE
J 2
(-6605 2580);
DISPLAY 0.872340 (-6605 2580);
PAINT GREEN (-6605 2580);
DISPLAY INVISIBLE (-6605 2580);
FORCEPROP 2 LAST PATH I255
J 0
(-6850 2725);
DISPLAY 1.021277 (-6850 2725);
DISPLAY INVISIBLE (-6850 2725);
FORCEADD OFFPAGE..2
R 2
(-7025 2575);
FORCEPROP 2 LAST $XR0 210 
J 0
(-7280 2575);
DISPLAY 0.638298 (-7280 2575);
PAINT MONO (-7280 2575);
FORCEPROP 2 LAST CDS_LIB standard
J 0
(-7025 2575);
DISPLAY INVISIBLE (-7025 2575);
FORCEPROP 1 LAST OFFPAGE TRUE
J 2
(-7350 2450);
DISPLAY 0.872340 (-7350 2450);
PAINT GREEN (-7350 2450);
DISPLAY INVISIBLE (-7350 2450);
FORCEPROP 1 LAST COMMENT_BODY TRUE
J 2
(-6980 2480);
DISPLAY 0.872340 (-6980 2480);
PAINT GREEN (-6980 2480);
DISPLAY INVISIBLE (-6980 2480);
FORCEPROP 2 LAST PATH I256
J 0
(-7275 2625);
DISPLAY 1.021277 (-7275 2625);
DISPLAY INVISIBLE (-7275 2625);
FORCEADD OFFPAGE..2
R 2
(-7025 2525);
FORCEPROP 2 LAST $XR0 217 
J 0
(-7280 2525);
DISPLAY 0.638298 (-7280 2525);
PAINT MONO (-7280 2525);
FORCEPROP 2 LAST CDS_LIB standard
J 0
(-7025 2525);
DISPLAY INVISIBLE (-7025 2525);
FORCEPROP 1 LAST OFFPAGE TRUE
J 2
(-7350 2400);
DISPLAY 0.872340 (-7350 2400);
PAINT GREEN (-7350 2400);
DISPLAY INVISIBLE (-7350 2400);
FORCEPROP 1 LAST COMMENT_BODY TRUE
J 2
(-6980 2430);
DISPLAY 0.872340 (-6980 2430);
PAINT GREEN (-6980 2430);
DISPLAY INVISIBLE (-6980 2430);
FORCEPROP 2 LAST PATH I257
J 0
(-7275 2575);
DISPLAY 1.021277 (-7275 2575);
DISPLAY INVISIBLE (-7275 2575);
FORCEADD OFFPAGE..2
R 2
(-7025 2475);
FORCEPROP 2 LAST $XR1 224 
J 0
(-7400 2475);
DISPLAY 0.638298 (-7400 2475);
PAINT MONO (-7400 2475);
FORCEPROP 2 LAST $XR0 217 
J 0
(-7280 2475);
DISPLAY 0.638298 (-7280 2475);
PAINT MONO (-7280 2475);
FORCEPROP 2 LAST CDS_LIB standard
J 0
(-7025 2475);
DISPLAY INVISIBLE (-7025 2475);
FORCEPROP 1 LAST OFFPAGE TRUE
J 2
(-7350 2350);
DISPLAY 0.872340 (-7350 2350);
PAINT GREEN (-7350 2350);
DISPLAY INVISIBLE (-7350 2350);
FORCEPROP 1 LAST COMMENT_BODY TRUE
J 2
(-6980 2380);
DISPLAY 0.872340 (-6980 2380);
PAINT GREEN (-6980 2380);
DISPLAY INVISIBLE (-6980 2380);
FORCEPROP 2 LAST PATH I258
J 0
(-7275 2525);
DISPLAY 1.021277 (-7275 2525);
DISPLAY INVISIBLE (-7275 2525);
FORCEADD OFFPAGE..2
R 2
(-7025 2425);
FORCEPROP 2 LAST $XR0 226 
J 0
(-7280 2425);
DISPLAY 0.638298 (-7280 2425);
PAINT MONO (-7280 2425);
FORCEPROP 2 LAST CDS_LIB standard
J 0
(-7025 2425);
DISPLAY INVISIBLE (-7025 2425);
FORCEPROP 1 LAST OFFPAGE TRUE
J 2
(-7350 2300);
DISPLAY 0.872340 (-7350 2300);
PAINT GREEN (-7350 2300);
DISPLAY INVISIBLE (-7350 2300);
FORCEPROP 1 LAST COMMENT_BODY TRUE
J 2
(-6980 2330);
DISPLAY 0.872340 (-6980 2330);
PAINT GREEN (-6980 2330);
DISPLAY INVISIBLE (-6980 2330);
FORCEPROP 2 LAST PATH I259
J 0
(-7275 2475);
DISPLAY 1.021277 (-7275 2475);
DISPLAY INVISIBLE (-7275 2475);
FORCEADD OFFPAGE..2
R 2
(-7025 2325);
FORCEPROP 2 LAST $XR0 217 
J 0
(-7280 2325);
DISPLAY 0.638298 (-7280 2325);
PAINT MONO (-7280 2325);
FORCEPROP 2 LAST CDS_LIB standard
J 0
(-7025 2325);
DISPLAY INVISIBLE (-7025 2325);
FORCEPROP 1 LAST OFFPAGE TRUE
J 2
(-7350 2200);
DISPLAY 0.872340 (-7350 2200);
PAINT GREEN (-7350 2200);
DISPLAY INVISIBLE (-7350 2200);
FORCEPROP 1 LAST COMMENT_BODY TRUE
J 2
(-6980 2230);
DISPLAY 0.872340 (-6980 2230);
PAINT GREEN (-6980 2230);
DISPLAY INVISIBLE (-6980 2230);
FORCEPROP 2 LAST PATH I260
J 0
(-7275 2375);
DISPLAY 1.021277 (-7275 2375);
DISPLAY INVISIBLE (-7275 2375);
FORCEADD OFFPAGE..2
R 2
(-7025 2225);
FORCEPROP 2 LAST $XR0 210 
J 0
(-7280 2225);
DISPLAY 0.638298 (-7280 2225);
PAINT MONO (-7280 2225);
FORCEPROP 2 LAST CDS_LIB standard
J 0
(-7025 2225);
DISPLAY INVISIBLE (-7025 2225);
FORCEPROP 1 LAST OFFPAGE TRUE
J 2
(-7350 2100);
DISPLAY 0.872340 (-7350 2100);
PAINT GREEN (-7350 2100);
DISPLAY INVISIBLE (-7350 2100);
FORCEPROP 1 LAST COMMENT_BODY TRUE
J 2
(-6980 2130);
DISPLAY 0.872340 (-6980 2130);
PAINT GREEN (-6980 2130);
DISPLAY INVISIBLE (-6980 2130);
FORCEPROP 2 LAST PATH I261
J 0
(-7275 2275);
DISPLAY 1.021277 (-7275 2275);
DISPLAY INVISIBLE (-7275 2275);
FORCEADD OFFPAGE..2
R 2
(-7025 2275);
FORCEPROP 2 LAST $XR0 217 
J 0
(-7280 2275);
DISPLAY 0.638298 (-7280 2275);
PAINT MONO (-7280 2275);
FORCEPROP 2 LAST CDS_LIB standard
J 0
(-7025 2275);
DISPLAY INVISIBLE (-7025 2275);
FORCEPROP 1 LAST OFFPAGE TRUE
J 2
(-7350 2150);
DISPLAY 0.872340 (-7350 2150);
PAINT GREEN (-7350 2150);
DISPLAY INVISIBLE (-7350 2150);
FORCEPROP 1 LAST COMMENT_BODY TRUE
J 2
(-6980 2180);
DISPLAY 0.872340 (-6980 2180);
PAINT GREEN (-6980 2180);
DISPLAY INVISIBLE (-6980 2180);
FORCEPROP 2 LAST PATH I262
J 0
(-7275 2325);
DISPLAY 1.021277 (-7275 2325);
DISPLAY INVISIBLE (-7275 2325);
FORCEADD OFFPAGE..2
R 2
(-7025 2175);
FORCEPROP 2 LAST $XR0 224 
J 0
(-7280 2175);
DISPLAY 0.638298 (-7280 2175);
PAINT MONO (-7280 2175);
FORCEPROP 2 LAST CDS_LIB standard
J 0
(-7025 2175);
DISPLAY INVISIBLE (-7025 2175);
FORCEPROP 1 LAST OFFPAGE TRUE
J 2
(-7350 2050);
DISPLAY 0.872340 (-7350 2050);
PAINT GREEN (-7350 2050);
DISPLAY INVISIBLE (-7350 2050);
FORCEPROP 1 LAST COMMENT_BODY TRUE
J 2
(-6980 2080);
DISPLAY 0.872340 (-6980 2080);
PAINT GREEN (-6980 2080);
DISPLAY INVISIBLE (-6980 2080);
FORCEPROP 2 LAST PATH I263
J 0
(-7275 2225);
DISPLAY 1.021277 (-7275 2225);
DISPLAY INVISIBLE (-7275 2225);
FORCEADD TP..1
R 6
(-6825 1900);
FORCEPROP 1 LAST LOCATION TP12
J 1
(-6825 1802);
DISPLAY 0.489362 (-6825 1802);
PAINT SKYBLUE (-6825 1802);
FORCEPROP 0 LAST $SEC 1
J 0
(-6850 1875);
DISPLAY 0.680851 (-6850 1875);
PAINT MONO (-6850 1875);
DISPLAY INVISIBLE (-6850 1875);
FORCEPROP 0 LAST CDS_SEC 1
J 0
(-6850 1875);
DISPLAY 1.021277 (-6850 1875);
DISPLAY INVISIBLE (-6850 1875);
FORCEPROP 0 LASTPIN (-6825 1950) $PN 1
R 1
J 0
(-6835 1960);
DISPLAY 0.489362 (-6835 1960);
PAINT MONO (-6835 1960);
FORCEPROP 1 LAST MATERIAL NA
J 0
(-6850 1852);
DISPLAY 0.489362 (-6850 1852);
PAINT SKYBLUE (-6850 1852);
FORCEPROP 1 LAST PACK_TYPE TP
J 1
(-6770 1944);
DISPLAY 0.446809 (-6770 1944);
PAINT SKYBLUE (-6770 1944);
DISPLAY INVISIBLE (-6770 1944);
FORCEPROP 1 LASTPIN (-6825 1950) $PIN_NUMBER ?
J 2
(-6775 1950);
DISPLAY 0.702128 (-6775 1950);
PAINT MONO (-6775 1950);
DISPLAY INVISIBLE (-6775 1950);
FORCEPROP 2 LAST CDS_LIB pure_quanta
J 0
(-6825 1900);
DISPLAY INVISIBLE (-6825 1900);
FORCEPROP 1 LAST PATH I272
J 1
(-6820 1855);
DISPLAY 0.446809 (-6820 1855);
PAINT GREEN (-6820 1855);
DISPLAY INVISIBLE (-6820 1855);
FORCEPROP 1 LAST PART_NUMBER TP30
J 1
(-6770 1924);
DISPLAY 0.446809 (-6770 1924);
PAINT SKYBLUE (-6770 1924);
DISPLAY INVISIBLE (-6770 1924);
FORCEADD TP..1
R 6
(-6900 1900);
FORCEPROP 1 LAST LOCATION TP11
J 1
(-6900 1802);
DISPLAY 0.489362 (-6900 1802);
PAINT SKYBLUE (-6900 1802);
FORCEPROP 0 LAST $SEC 1
J 0
(-6925 1875);
DISPLAY 0.680851 (-6925 1875);
PAINT MONO (-6925 1875);
DISPLAY INVISIBLE (-6925 1875);
FORCEPROP 0 LAST CDS_SEC 1
J 0
(-6925 1875);
DISPLAY 1.021277 (-6925 1875);
DISPLAY INVISIBLE (-6925 1875);
FORCEPROP 0 LASTPIN (-6900 1950) $PN 1
R 1
J 0
(-6910 1960);
DISPLAY 0.489362 (-6910 1960);
PAINT MONO (-6910 1960);
FORCEPROP 1 LAST MATERIAL NA
J 0
(-6925 1852);
DISPLAY 0.489362 (-6925 1852);
PAINT SKYBLUE (-6925 1852);
FORCEPROP 1 LAST PACK_TYPE TP
J 1
(-6845 1944);
DISPLAY 0.446809 (-6845 1944);
PAINT SKYBLUE (-6845 1944);
DISPLAY INVISIBLE (-6845 1944);
FORCEPROP 1 LASTPIN (-6900 1950) $PIN_NUMBER ?
J 2
(-6850 1950);
DISPLAY 0.702128 (-6850 1950);
PAINT MONO (-6850 1950);
DISPLAY INVISIBLE (-6850 1950);
FORCEPROP 2 LAST CDS_LIB pure_quanta
J 0
(-6900 1900);
DISPLAY INVISIBLE (-6900 1900);
FORCEPROP 1 LAST PATH I273
J 1
(-6895 1855);
DISPLAY 0.446809 (-6895 1855);
PAINT GREEN (-6895 1855);
DISPLAY INVISIBLE (-6895 1855);
FORCEPROP 1 LAST PART_NUMBER TP30
J 1
(-6845 1924);
DISPLAY 0.446809 (-6845 1924);
PAINT SKYBLUE (-6845 1924);
DISPLAY INVISIBLE (-6845 1924);
FORCEADD OFFPAGE..2
R 2
(-7025 2075);
FORCEPROP 2 LAST $XR0 226 
J 0
(-7280 2075);
DISPLAY 0.638298 (-7280 2075);
PAINT MONO (-7280 2075);
FORCEPROP 2 LAST CDS_LIB standard
J 0
(-7025 2075);
DISPLAY INVISIBLE (-7025 2075);
FORCEPROP 1 LAST OFFPAGE TRUE
J 2
(-7350 1950);
DISPLAY 0.872340 (-7350 1950);
PAINT GREEN (-7350 1950);
DISPLAY INVISIBLE (-7350 1950);
FORCEPROP 1 LAST COMMENT_BODY TRUE
J 2
(-6980 1980);
DISPLAY 0.872340 (-6980 1980);
PAINT GREEN (-6980 1980);
DISPLAY INVISIBLE (-6980 1980);
FORCEPROP 2 LAST PATH I274
J 0
(-7275 2125);
DISPLAY 1.021277 (-7275 2125);
DISPLAY INVISIBLE (-7275 2125);
FORCEADD OFFPAGE..2
R 2
(-7025 2025);
FORCEPROP 2 LAST $XR0 210 
J 0
(-7280 2025);
DISPLAY 0.638298 (-7280 2025);
PAINT MONO (-7280 2025);
FORCEPROP 2 LAST CDS_LIB standard
J 0
(-7025 2025);
DISPLAY INVISIBLE (-7025 2025);
FORCEPROP 1 LAST OFFPAGE TRUE
J 2
(-7350 1900);
DISPLAY 0.872340 (-7350 1900);
PAINT GREEN (-7350 1900);
DISPLAY INVISIBLE (-7350 1900);
FORCEPROP 1 LAST COMMENT_BODY TRUE
J 2
(-6980 1930);
DISPLAY 0.872340 (-6980 1930);
PAINT GREEN (-6980 1930);
DISPLAY INVISIBLE (-6980 1930);
FORCEPROP 2 LAST PATH I275
J 0
(-7275 2075);
DISPLAY 1.021277 (-7275 2075);
DISPLAY INVISIBLE (-7275 2075);
FORCEADD UNIVERSAL_POWER..1
(-8750 5000);
FORCEPROP 3 LASTPIN (-8750 4950) SIG_NAME PVDD18_S5_P1\g
J 0
(-8740 4960);
DISPLAY 0.659574 (-8740 4960);
PAINT MONO (-8740 4960);
DISPLAY INVISIBLE (-8740 4960);
FORCEPROP 1 LAST HDL_POWER PVDD18_S5_P1
J 1
(-8750 5050);
DISPLAY 0.489362 (-8750 5050);
PAINT GREEN (-8750 5050);
FORCEPROP 2 LAST CDS_LIB pure_quanta_power
J 0
(-8750 5000);
DISPLAY INVISIBLE (-8750 5000);
FORCEPROP 1 LAST PATH I286
J 0
(-8700 5025);
DISPLAY 0.872340 (-8700 5025);
PAINT AQUA (-8700 5025);
DISPLAY INVISIBLE (-8700 5025);
FORCEADD GND..1
(-8625 4275);
FORCEPROP 3 LASTPIN (-8625 4325) SIG_NAME GND\g
J 0
(-8615 4335);
DISPLAY 0.659574 (-8615 4335);
PAINT MONO (-8615 4335);
DISPLAY INVISIBLE (-8615 4335);
FORCEPROP 2 LAST CDS_LIB pure_quanta_power
J 0
(-8625 4275);
DISPLAY INVISIBLE (-8625 4275);
FORCEPROP 1 LAST SIZE 1B
J 0
(-8550 4225);
DISPLAY 0.872340 (-8550 4225);
PAINT GREEN (-8550 4225);
DISPLAY INVISIBLE (-8550 4225);
FORCEPROP 1 LAST HDL_POWER GND
J 0
(-8625 4425);
DISPLAY 0.872340 (-8625 4425);
PAINT GREEN (-8625 4425);
DISPLAY INVISIBLE (-8625 4425);
FORCEPROP 1 LAST PATH I289
J 0
(-8550 4275);
DISPLAY 0.872340 (-8550 4275);
PAINT AQUA (-8550 4275);
DISPLAY INVISIBLE (-8550 4275);
FORCEADD GND..1
(-8750 4275);
FORCEPROP 3 LASTPIN (-8750 4325) SIG_NAME GND\g
J 0
(-8740 4335);
DISPLAY 0.659574 (-8740 4335);
PAINT MONO (-8740 4335);
DISPLAY INVISIBLE (-8740 4335);
FORCEPROP 2 LAST CDS_LIB pure_quanta_power
J 0
(-8750 4275);
DISPLAY INVISIBLE (-8750 4275);
FORCEPROP 1 LAST SIZE 1B
J 0
(-8675 4225);
DISPLAY 0.872340 (-8675 4225);
PAINT GREEN (-8675 4225);
DISPLAY INVISIBLE (-8675 4225);
FORCEPROP 1 LAST HDL_POWER GND
J 0
(-8750 4425);
DISPLAY 0.872340 (-8750 4425);
PAINT GREEN (-8750 4425);
DISPLAY INVISIBLE (-8750 4425);
FORCEPROP 1 LAST PATH I291
J 0
(-8675 4275);
DISPLAY 0.872340 (-8675 4275);
PAINT AQUA (-8675 4275);
DISPLAY INVISIBLE (-8675 4275);
FORCEADD Q_RES..2
(-6725 1325);
FORCEPROP 1 LAST LOCATION R528
J 0
(-6700 1425);
DISPLAY 0.489362 (-6700 1425);
PAINT SKYBLUE (-6700 1425);
FORCEPROP 0 LAST $SEC 1
J 0
(-6700 1475);
DISPLAY 0.680851 (-6700 1475);
PAINT MONO (-6700 1475);
DISPLAY INVISIBLE (-6700 1475);
FORCEPROP 0 LAST CDS_SEC 1
J 0
(-6700 1475);
DISPLAY 1.021277 (-6700 1475);
DISPLAY INVISIBLE (-6700 1475);
FORCEPROP 1 LASTPIN (-6725 1425) $PN 1
J 0
(-6720 1387);
DISPLAY 0.489362 (-6720 1387);
PAINT MONO (-6720 1387);
FORCEPROP 1 LASTPIN (-6725 1225) $PN 2
J 0
(-6720 1235);
DISPLAY 0.489362 (-6720 1235);
PAINT MONO (-6720 1235);
FORCEPROP 1 LAST TOLERANCE 1%
J 0
(-6700 1325);
DISPLAY 0.489362 (-6700 1325);
PAINT SKYBLUE (-6700 1325);
FORCEPROP 1 LAST WATTAGE 1/16W
J 0
(-6700 1275);
DISPLAY 0.489362 (-6700 1275);
PAINT SKYBLUE (-6700 1275);
FORCEPROP 1 LAST MATERIAL CHIP
J 0
(-6700 1225);
DISPLAY 0.489362 (-6700 1225);
PAINT SKYBLUE (-6700 1225);
FORCEPROP 1 LAST VALUE 1K
J 0
(-6700 1375);
DISPLAY 0.489362 (-6700 1375);
PAINT SKYBLUE (-6700 1375);
FORCEPROP 1 LAST PACK_TYPE 0402LF
J 0
(-6700 1175);
DISPLAY 0.489362 (-6700 1175);
PAINT SKYBLUE (-6700 1175);
FORCEPROP 2 LAST CDS_LIB pure_quanta
J 0
(-6725 1325);
DISPLAY INVISIBLE (-6725 1325);
FORCEPROP 1 LAST PATH I308
J 0
(-6675 1500);
DISPLAY 0.978723 (-6675 1500);
PAINT WHITE (-6675 1500);
DISPLAY INVISIBLE (-6675 1500);
FORCEPROP 1 LAST PART_NUMBER CS21002FB06
J 0
(-6700 1125);
DISPLAY 0.489362 (-6700 1125);
PAINT SKYBLUE (-6700 1125);
DISPLAY INVISIBLE (-6700 1125);
FORCEADD Q_RES..2
(-7000 1325);
FORCEPROP 1 LAST LOCATION R527
J 0
(-6975 1425);
DISPLAY 0.489362 (-6975 1425);
PAINT SKYBLUE (-6975 1425);
FORCEPROP 2 LAST $SEC 1
J 0
(-6950 1550);
DISPLAY 0.680851 (-6950 1550);
PAINT MONO (-6950 1550);
DISPLAY INVISIBLE (-6950 1550);
FORCEPROP 2 LAST CDS_SEC 1
J 0
(-6950 1550);
DISPLAY 1.021277 (-6950 1550);
DISPLAY INVISIBLE (-6950 1550);
FORCEPROP 1 LASTPIN (-7000 1425) $PN 1
J 0
(-6995 1387);
DISPLAY 0.489362 (-6995 1387);
FORCEPROP 1 LASTPIN (-7000 1225) $PN 2
J 0
(-6995 1235);
DISPLAY 0.489362 (-6995 1235);
FORCEPROP 1 LAST TOLERANCE 1%
J 0
(-6975 1325);
DISPLAY 0.489362 (-6975 1325);
PAINT SKYBLUE (-6975 1325);
FORCEPROP 1 LAST WATTAGE 1/16W
J 0
(-6975 1275);
DISPLAY 0.489362 (-6975 1275);
PAINT SKYBLUE (-6975 1275);
FORCEPROP 1 LAST MATERIAL CHIP
J 0
(-6975 1225);
DISPLAY 0.489362 (-6975 1225);
PAINT SKYBLUE (-6975 1225);
FORCEPROP 1 LAST VALUE 1K
J 0
(-6975 1375);
DISPLAY 0.489362 (-6975 1375);
PAINT SKYBLUE (-6975 1375);
FORCEPROP 1 LAST PACK_TYPE 0402LF
J 0
(-6975 1175);
DISPLAY 0.489362 (-6975 1175);
PAINT SKYBLUE (-6975 1175);
FORCEPROP 2 LAST CDS_LIB pure_quanta
J 0
(-7000 1325);
DISPLAY INVISIBLE (-7000 1325);
FORCEPROP 1 LAST PATH I309
J 0
(-6950 1500);
DISPLAY 0.978723 (-6950 1500);
PAINT WHITE (-6950 1500);
DISPLAY INVISIBLE (-6950 1500);
FORCEPROP 1 LAST PART_NUMBER CS21002FB06
J 0
(-6960 1200);
DISPLAY 0.617021 (-6960 1200);
PAINT SKYBLUE (-6960 1200);
DISPLAY INVISIBLE (-6960 1200);
FORCEADD Q_CAP..1
(-6725 625);
FORCEPROP 1 LAST LOCATION C235
J 0
(-6675 725);
DISPLAY 0.489362 (-6675 725);
PAINT SKYBLUE (-6675 725);
FORCEPROP 0 LAST $SEC 1
J 0
(-6675 775);
DISPLAY 0.680851 (-6675 775);
PAINT MONO (-6675 775);
DISPLAY INVISIBLE (-6675 775);
FORCEPROP 0 LAST CDS_SEC 1
J 0
(-6675 775);
DISPLAY 1.021277 (-6675 775);
DISPLAY INVISIBLE (-6675 775);
FORCEPROP 1 LASTPIN (-6725 725) $PN 1
J 0
(-6715 705);
DISPLAY 0.489362 (-6715 705);
PAINT MONO (-6715 705);
FORCEPROP 1 LASTPIN (-6725 525) $PN 2
J 0
(-6715 505);
DISPLAY 0.489362 (-6715 505);
PAINT MONO (-6715 505);
FORCEPROP 1 LAST PACK_TYPE C0402
J 0
(-6675 475);
DISPLAY 0.489362 (-6675 475);
PAINT SKYBLUE (-6675 475);
FORCEPROP 1 LAST VOLTAGE 50V
J 0
(-6675 625);
DISPLAY 0.489362 (-6675 625);
PAINT SKYBLUE (-6675 625);
FORCEPROP 1 LAST VALUE 0.001UF
J 0
(-6675 675);
DISPLAY 0.489362 (-6675 675);
PAINT SKYBLUE (-6675 675);
FORCEPROP 1 LAST TOLERANCE 10%
J 0
(-6675 575);
DISPLAY 0.489362 (-6675 575);
PAINT SKYBLUE (-6675 575);
FORCEPROP 1 LAST MATERIAL EMPTY
J 0
(-6675 425);
DISPLAY 0.489362 (-6675 425);
PAINT RED (-6675 425);
FORCEPROP 2 LAST CDS_LIB pure_quanta
J 0
(-6725 625);
DISPLAY INVISIBLE (-6725 625);
FORCEPROP 1 LAST PATH I310
J 0
(-6675 775);
DISPLAY 0.978723 (-6675 775);
PAINT WHITE (-6675 775);
DISPLAY INVISIBLE (-6675 775);
FORCEPROP 1 LAST PART_NUMBER CH30106KB19
J 0
(-6675 525);
DISPLAY 0.489362 (-6675 525);
PAINT SKYBLUE (-6675 525);
DISPLAY INVISIBLE (-6675 525);
FORCEADD Q_CAP..1
(-7000 625);
FORCEPROP 1 LAST LOCATION C234
J 0
(-6950 725);
DISPLAY 0.489362 (-6950 725);
PAINT SKYBLUE (-6950 725);
FORCEPROP 0 LAST $SEC 1
J 0
(-6950 775);
PAINT MONO (-6950 775);
DISPLAY INVISIBLE (-6950 775);
FORCEPROP 0 LAST CDS_SEC 1
J 0
(-6950 775);
PAINT MONO (-6950 775);
DISPLAY INVISIBLE (-6950 775);
FORCEPROP 1 LASTPIN (-7000 725) $PN 1
J 0
(-6990 705);
DISPLAY 0.489362 (-6990 705);
PAINT GREEN (-6990 705);
FORCEPROP 1 LASTPIN (-7000 525) $PN 2
J 0
(-6990 505);
DISPLAY 0.489362 (-6990 505);
PAINT GREEN (-6990 505);
FORCEPROP 1 LAST PACK_TYPE C0402
J 0
(-6950 475);
DISPLAY 0.489362 (-6950 475);
PAINT SKYBLUE (-6950 475);
FORCEPROP 1 LAST VOLTAGE 50V
J 0
(-6950 625);
DISPLAY 0.489362 (-6950 625);
PAINT SKYBLUE (-6950 625);
FORCEPROP 1 LAST VALUE 0.001UF
J 0
(-6950 675);
DISPLAY 0.489362 (-6950 675);
PAINT SKYBLUE (-6950 675);
FORCEPROP 1 LAST TOLERANCE 10%
J 0
(-6950 575);
DISPLAY 0.489362 (-6950 575);
PAINT SKYBLUE (-6950 575);
FORCEPROP 1 LAST MATERIAL EMPTY
J 0
(-6950 425);
DISPLAY 0.489362 (-6950 425);
PAINT RED (-6950 425);
FORCEPROP 2 LAST CDS_LIB pure_quanta
J 0
(-7000 625);
PAINT MONO (-7000 625);
DISPLAY INVISIBLE (-7000 625);
FORCEPROP 1 LAST PATH I311
J 0
(-6950 775);
DISPLAY 0.978723 (-6950 775);
PAINT WHITE (-6950 775);
DISPLAY INVISIBLE (-6950 775);
FORCEPROP 1 LAST PART_NUMBER CH30106KB19
J 0
(-6950 525);
DISPLAY 0.808511 (-6950 525);
PAINT SKYBLUE (-6950 525);
DISPLAY INVISIBLE (-6950 525);
FORCEADD GND..1
(-6725 325);
FORCEPROP 3 LASTPIN (-6725 375) SIG_NAME GND\g
J 0
(-6715 385);
DISPLAY 0.659574 (-6715 385);
PAINT MONO (-6715 385);
DISPLAY INVISIBLE (-6715 385);
FORCEPROP 2 LAST CDS_LIB pure_quanta_power
J 0
(-6725 325);
DISPLAY INVISIBLE (-6725 325);
FORCEPROP 1 LAST SIZE 1B
J 0
(-6650 275);
DISPLAY 0.872340 (-6650 275);
PAINT GREEN (-6650 275);
DISPLAY INVISIBLE (-6650 275);
FORCEPROP 1 LAST HDL_POWER GND
J 0
(-6725 475);
DISPLAY 0.872340 (-6725 475);
PAINT GREEN (-6725 475);
DISPLAY INVISIBLE (-6725 475);
FORCEPROP 1 LAST PATH I312
J 0
(-6650 325);
DISPLAY 0.872340 (-6650 325);
PAINT AQUA (-6650 325);
DISPLAY INVISIBLE (-6650 325);
FORCEADD GND..1
(-7000 325);
FORCEPROP 3 LASTPIN (-7000 375) SIG_NAME GND\g
J 0
(-6990 385);
DISPLAY 0.659574 (-6990 385);
PAINT MONO (-6990 385);
DISPLAY INVISIBLE (-6990 385);
FORCEPROP 1 LAST SIZE 1B
J 0
(-6925 275);
DISPLAY 0.872340 (-6925 275);
PAINT GREEN (-6925 275);
DISPLAY INVISIBLE (-6925 275);
FORCEPROP 2 LAST CDS_LIB pure_quanta_power
J 0
(-7000 325);
DISPLAY INVISIBLE (-7000 325);
FORCEPROP 1 LAST HDL_POWER GND
J 0
(-7000 475);
DISPLAY 0.872340 (-7000 475);
PAINT GREEN (-7000 475);
DISPLAY INVISIBLE (-7000 475);
FORCEPROP 1 LAST PATH I313
J 0
(-6925 325);
DISPLAY 0.872340 (-6925 325);
PAINT AQUA (-6925 325);
DISPLAY INVISIBLE (-6925 325);
FORCEADD Q_RES..2
(-7300 1325);
FORCEPROP 1 LAST LOCATION R526
J 0
(-7275 1425);
DISPLAY 0.489362 (-7275 1425);
PAINT SKYBLUE (-7275 1425);
FORCEPROP 2 LAST $SEC 1
J 0
(-7250 1550);
DISPLAY 0.680851 (-7250 1550);
PAINT MONO (-7250 1550);
DISPLAY INVISIBLE (-7250 1550);
FORCEPROP 2 LAST CDS_SEC 1
J 0
(-7250 1550);
DISPLAY 1.021277 (-7250 1550);
DISPLAY INVISIBLE (-7250 1550);
FORCEPROP 1 LASTPIN (-7300 1425) $PN 1
J 0
(-7295 1387);
DISPLAY 0.489362 (-7295 1387);
FORCEPROP 1 LASTPIN (-7300 1225) $PN 2
J 0
(-7295 1235);
DISPLAY 0.489362 (-7295 1235);
FORCEPROP 1 LAST TOLERANCE 1%
J 0
(-7275 1325);
DISPLAY 0.489362 (-7275 1325);
PAINT SKYBLUE (-7275 1325);
FORCEPROP 1 LAST WATTAGE 1/16W
J 0
(-7275 1275);
DISPLAY 0.489362 (-7275 1275);
PAINT SKYBLUE (-7275 1275);
FORCEPROP 1 LAST MATERIAL CHIP
J 0
(-7275 1225);
DISPLAY 0.489362 (-7275 1225);
PAINT SKYBLUE (-7275 1225);
FORCEPROP 1 LAST VALUE 1K
J 0
(-7275 1375);
DISPLAY 0.489362 (-7275 1375);
PAINT SKYBLUE (-7275 1375);
FORCEPROP 1 LAST PACK_TYPE 0402LF
J 0
(-7275 1175);
DISPLAY 0.489362 (-7275 1175);
PAINT SKYBLUE (-7275 1175);
FORCEPROP 2 LAST CDS_LIB pure_quanta
J 0
(-7300 1325);
DISPLAY INVISIBLE (-7300 1325);
FORCEPROP 1 LAST PATH I314
J 0
(-7250 1500);
DISPLAY 0.978723 (-7250 1500);
PAINT WHITE (-7250 1500);
DISPLAY INVISIBLE (-7250 1500);
FORCEPROP 1 LAST PART_NUMBER CS21002FB06
J 0
(-7260 1200);
DISPLAY 0.617021 (-7260 1200);
PAINT SKYBLUE (-7260 1200);
DISPLAY INVISIBLE (-7260 1200);
FORCEADD Q_CAP..1
(-7300 625);
FORCEPROP 1 LAST LOCATION C233
J 0
(-7250 725);
DISPLAY 0.489362 (-7250 725);
PAINT SKYBLUE (-7250 725);
FORCEPROP 0 LAST $SEC 1
J 0
(-7250 775);
PAINT MONO (-7250 775);
DISPLAY INVISIBLE (-7250 775);
FORCEPROP 0 LAST CDS_SEC 1
J 0
(-7250 775);
PAINT MONO (-7250 775);
DISPLAY INVISIBLE (-7250 775);
FORCEPROP 1 LASTPIN (-7300 725) $PN 1
J 0
(-7290 705);
DISPLAY 0.489362 (-7290 705);
PAINT GREEN (-7290 705);
FORCEPROP 1 LASTPIN (-7300 525) $PN 2
J 0
(-7290 505);
DISPLAY 0.489362 (-7290 505);
PAINT GREEN (-7290 505);
FORCEPROP 1 LAST PACK_TYPE C0402
J 0
(-7250 475);
DISPLAY 0.489362 (-7250 475);
PAINT SKYBLUE (-7250 475);
FORCEPROP 1 LAST VOLTAGE 50V
J 0
(-7250 625);
DISPLAY 0.489362 (-7250 625);
PAINT SKYBLUE (-7250 625);
FORCEPROP 1 LAST VALUE 0.001UF
J 0
(-7250 675);
DISPLAY 0.489362 (-7250 675);
PAINT SKYBLUE (-7250 675);
FORCEPROP 1 LAST TOLERANCE 10%
J 0
(-7250 575);
DISPLAY 0.489362 (-7250 575);
PAINT SKYBLUE (-7250 575);
FORCEPROP 1 LAST MATERIAL EMPTY
J 0
(-7250 425);
DISPLAY 0.489362 (-7250 425);
PAINT RED (-7250 425);
FORCEPROP 2 LAST CDS_LIB pure_quanta
J 0
(-7300 625);
PAINT MONO (-7300 625);
DISPLAY INVISIBLE (-7300 625);
FORCEPROP 1 LAST PATH I315
J 0
(-7250 775);
DISPLAY 0.978723 (-7250 775);
PAINT WHITE (-7250 775);
DISPLAY INVISIBLE (-7250 775);
FORCEPROP 1 LAST PART_NUMBER CH30106KB19
J 0
(-7250 525);
DISPLAY 0.808511 (-7250 525);
PAINT SKYBLUE (-7250 525);
DISPLAY INVISIBLE (-7250 525);
FORCEADD Q_RES..2
(-7625 1325);
FORCEPROP 1 LAST LOCATION R525
J 0
(-7600 1425);
DISPLAY 0.489362 (-7600 1425);
PAINT SKYBLUE (-7600 1425);
FORCEPROP 2 LAST $SEC 1
J 0
(-7575 1550);
DISPLAY 0.680851 (-7575 1550);
PAINT MONO (-7575 1550);
DISPLAY INVISIBLE (-7575 1550);
FORCEPROP 2 LAST CDS_SEC 1
J 0
(-7575 1550);
DISPLAY 1.021277 (-7575 1550);
DISPLAY INVISIBLE (-7575 1550);
FORCEPROP 1 LASTPIN (-7625 1425) $PN 1
J 0
(-7620 1387);
DISPLAY 0.489362 (-7620 1387);
FORCEPROP 1 LASTPIN (-7625 1225) $PN 2
J 0
(-7620 1235);
DISPLAY 0.489362 (-7620 1235);
FORCEPROP 1 LAST TOLERANCE 1%
J 0
(-7600 1325);
DISPLAY 0.489362 (-7600 1325);
PAINT SKYBLUE (-7600 1325);
FORCEPROP 1 LAST WATTAGE 1/16W
J 0
(-7600 1275);
DISPLAY 0.489362 (-7600 1275);
PAINT SKYBLUE (-7600 1275);
FORCEPROP 1 LAST MATERIAL CHIP
J 0
(-7600 1225);
DISPLAY 0.489362 (-7600 1225);
PAINT SKYBLUE (-7600 1225);
FORCEPROP 1 LAST VALUE 1K
J 0
(-7600 1375);
DISPLAY 0.489362 (-7600 1375);
PAINT SKYBLUE (-7600 1375);
FORCEPROP 1 LAST PACK_TYPE 0402LF
J 0
(-7600 1175);
DISPLAY 0.489362 (-7600 1175);
PAINT SKYBLUE (-7600 1175);
FORCEPROP 2 LAST CDS_LIB pure_quanta
J 0
(-7625 1325);
DISPLAY INVISIBLE (-7625 1325);
FORCEPROP 1 LAST PATH I316
J 0
(-7575 1500);
DISPLAY 0.978723 (-7575 1500);
PAINT WHITE (-7575 1500);
DISPLAY INVISIBLE (-7575 1500);
FORCEPROP 1 LAST PART_NUMBER CS21002FB06
J 0
(-7585 1200);
DISPLAY 0.617021 (-7585 1200);
PAINT SKYBLUE (-7585 1200);
DISPLAY INVISIBLE (-7585 1200);
FORCEADD Q_RES..2
(-7950 1325);
FORCEPROP 1 LAST LOCATION R524
J 0
(-7925 1425);
DISPLAY 0.489362 (-7925 1425);
PAINT SKYBLUE (-7925 1425);
FORCEPROP 2 LAST $SEC 1
J 0
(-7900 1550);
DISPLAY 0.680851 (-7900 1550);
PAINT MONO (-7900 1550);
DISPLAY INVISIBLE (-7900 1550);
FORCEPROP 2 LAST CDS_SEC 1
J 0
(-7900 1550);
DISPLAY 1.021277 (-7900 1550);
DISPLAY INVISIBLE (-7900 1550);
FORCEPROP 1 LASTPIN (-7950 1425) $PN 1
J 0
(-7945 1387);
DISPLAY 0.489362 (-7945 1387);
FORCEPROP 1 LASTPIN (-7950 1225) $PN 2
J 0
(-7945 1235);
DISPLAY 0.489362 (-7945 1235);
FORCEPROP 1 LAST TOLERANCE 1%
J 0
(-7925 1325);
DISPLAY 0.489362 (-7925 1325);
PAINT SKYBLUE (-7925 1325);
FORCEPROP 1 LAST WATTAGE 1/16W
J 0
(-7925 1275);
DISPLAY 0.489362 (-7925 1275);
PAINT SKYBLUE (-7925 1275);
FORCEPROP 1 LAST MATERIAL CHIP
J 0
(-7925 1225);
DISPLAY 0.489362 (-7925 1225);
PAINT SKYBLUE (-7925 1225);
FORCEPROP 1 LAST VALUE 1K
J 0
(-7925 1375);
DISPLAY 0.489362 (-7925 1375);
PAINT SKYBLUE (-7925 1375);
FORCEPROP 1 LAST PACK_TYPE 0402LF
J 0
(-7925 1175);
DISPLAY 0.489362 (-7925 1175);
PAINT SKYBLUE (-7925 1175);
FORCEPROP 2 LAST CDS_LIB pure_quanta
J 0
(-7950 1325);
DISPLAY INVISIBLE (-7950 1325);
FORCEPROP 1 LAST PATH I317
J 0
(-7900 1500);
DISPLAY 0.978723 (-7900 1500);
PAINT WHITE (-7900 1500);
DISPLAY INVISIBLE (-7900 1500);
FORCEPROP 1 LAST PART_NUMBER CS21002FB06
J 0
(-7910 1200);
DISPLAY 0.617021 (-7910 1200);
PAINT SKYBLUE (-7910 1200);
DISPLAY INVISIBLE (-7910 1200);
FORCEADD Q_CAP..1
(-7625 625);
FORCEPROP 1 LAST LOCATION C232
J 0
(-7575 725);
DISPLAY 0.489362 (-7575 725);
PAINT SKYBLUE (-7575 725);
FORCEPROP 0 LAST $SEC 1
J 0
(-7575 775);
PAINT MONO (-7575 775);
DISPLAY INVISIBLE (-7575 775);
FORCEPROP 0 LAST CDS_SEC 1
J 0
(-7575 775);
PAINT MONO (-7575 775);
DISPLAY INVISIBLE (-7575 775);
FORCEPROP 1 LASTPIN (-7625 725) $PN 1
J 0
(-7615 705);
DISPLAY 0.489362 (-7615 705);
PAINT GREEN (-7615 705);
FORCEPROP 1 LASTPIN (-7625 525) $PN 2
J 0
(-7615 505);
DISPLAY 0.489362 (-7615 505);
PAINT GREEN (-7615 505);
FORCEPROP 1 LAST PACK_TYPE C0402
J 0
(-7575 475);
DISPLAY 0.489362 (-7575 475);
PAINT SKYBLUE (-7575 475);
FORCEPROP 1 LAST VOLTAGE 50V
J 0
(-7575 625);
DISPLAY 0.489362 (-7575 625);
PAINT SKYBLUE (-7575 625);
FORCEPROP 1 LAST VALUE 0.001UF
J 0
(-7575 675);
DISPLAY 0.489362 (-7575 675);
PAINT SKYBLUE (-7575 675);
FORCEPROP 1 LAST TOLERANCE 10%
J 0
(-7575 575);
DISPLAY 0.489362 (-7575 575);
PAINT SKYBLUE (-7575 575);
FORCEPROP 1 LAST MATERIAL EMPTY
J 0
(-7575 425);
DISPLAY 0.489362 (-7575 425);
PAINT RED (-7575 425);
FORCEPROP 2 LAST CDS_LIB pure_quanta
J 0
(-7625 625);
PAINT MONO (-7625 625);
DISPLAY INVISIBLE (-7625 625);
FORCEPROP 1 LAST PATH I318
J 0
(-7575 775);
DISPLAY 0.978723 (-7575 775);
PAINT WHITE (-7575 775);
DISPLAY INVISIBLE (-7575 775);
FORCEPROP 1 LAST PART_NUMBER CH30106KB19
J 0
(-7575 525);
DISPLAY 0.808511 (-7575 525);
PAINT SKYBLUE (-7575 525);
DISPLAY INVISIBLE (-7575 525);
FORCEADD Q_CAP..1
(-7950 625);
FORCEPROP 1 LAST LOCATION C231
J 0
(-7900 725);
DISPLAY 0.489362 (-7900 725);
PAINT SKYBLUE (-7900 725);
FORCEPROP 0 LAST $SEC 1
J 0
(-7900 775);
PAINT MONO (-7900 775);
DISPLAY INVISIBLE (-7900 775);
FORCEPROP 0 LAST CDS_SEC 1
J 0
(-7900 775);
PAINT MONO (-7900 775);
DISPLAY INVISIBLE (-7900 775);
FORCEPROP 1 LASTPIN (-7950 725) $PN 1
J 0
(-7940 705);
DISPLAY 0.489362 (-7940 705);
PAINT GREEN (-7940 705);
FORCEPROP 1 LASTPIN (-7950 525) $PN 2
J 0
(-7940 505);
DISPLAY 0.489362 (-7940 505);
PAINT GREEN (-7940 505);
FORCEPROP 1 LAST PACK_TYPE C0402
J 0
(-7900 475);
DISPLAY 0.489362 (-7900 475);
PAINT SKYBLUE (-7900 475);
FORCEPROP 1 LAST VOLTAGE 50V
J 0
(-7900 625);
DISPLAY 0.489362 (-7900 625);
PAINT SKYBLUE (-7900 625);
FORCEPROP 1 LAST VALUE 0.001UF
J 0
(-7900 675);
DISPLAY 0.489362 (-7900 675);
PAINT SKYBLUE (-7900 675);
FORCEPROP 1 LAST TOLERANCE 10%
J 0
(-7900 575);
DISPLAY 0.489362 (-7900 575);
PAINT SKYBLUE (-7900 575);
FORCEPROP 1 LAST MATERIAL EMPTY
J 0
(-7900 425);
DISPLAY 0.489362 (-7900 425);
PAINT RED (-7900 425);
FORCEPROP 2 LAST CDS_LIB pure_quanta
J 0
(-7950 625);
PAINT MONO (-7950 625);
DISPLAY INVISIBLE (-7950 625);
FORCEPROP 1 LAST PATH I319
J 0
(-7900 775);
DISPLAY 0.978723 (-7900 775);
PAINT WHITE (-7900 775);
DISPLAY INVISIBLE (-7900 775);
FORCEPROP 1 LAST PART_NUMBER CH30106KB19
J 0
(-7900 525);
DISPLAY 0.808511 (-7900 525);
PAINT SKYBLUE (-7900 525);
DISPLAY INVISIBLE (-7900 525);
FORCEADD GND..1
(-7300 325);
FORCEPROP 3 LASTPIN (-7300 375) SIG_NAME GND\g
J 0
(-7290 385);
DISPLAY 0.659574 (-7290 385);
PAINT MONO (-7290 385);
DISPLAY INVISIBLE (-7290 385);
FORCEPROP 2 LAST CDS_LIB pure_quanta_power
J 0
(-7300 325);
DISPLAY INVISIBLE (-7300 325);
FORCEPROP 1 LAST SIZE 1B
J 0
(-7225 275);
DISPLAY 0.872340 (-7225 275);
PAINT GREEN (-7225 275);
DISPLAY INVISIBLE (-7225 275);
FORCEPROP 1 LAST HDL_POWER GND
J 0
(-7300 475);
DISPLAY 0.872340 (-7300 475);
PAINT GREEN (-7300 475);
DISPLAY INVISIBLE (-7300 475);
FORCEPROP 1 LAST PATH I320
J 0
(-7225 325);
DISPLAY 0.872340 (-7225 325);
PAINT AQUA (-7225 325);
DISPLAY INVISIBLE (-7225 325);
FORCEADD GND..1
(-7625 325);
FORCEPROP 3 LASTPIN (-7625 375) SIG_NAME GND\g
J 0
(-7615 385);
DISPLAY 0.659574 (-7615 385);
PAINT MONO (-7615 385);
DISPLAY INVISIBLE (-7615 385);
FORCEPROP 2 LAST CDS_LIB pure_quanta_power
J 0
(-7625 325);
DISPLAY INVISIBLE (-7625 325);
FORCEPROP 1 LAST SIZE 1B
J 0
(-7550 275);
DISPLAY 0.872340 (-7550 275);
PAINT GREEN (-7550 275);
DISPLAY INVISIBLE (-7550 275);
FORCEPROP 1 LAST HDL_POWER GND
J 0
(-7625 475);
DISPLAY 0.872340 (-7625 475);
PAINT GREEN (-7625 475);
DISPLAY INVISIBLE (-7625 475);
FORCEPROP 1 LAST PATH I321
J 0
(-7550 325);
DISPLAY 0.872340 (-7550 325);
PAINT AQUA (-7550 325);
DISPLAY INVISIBLE (-7550 325);
FORCEADD GND..1
(-7950 325);
FORCEPROP 3 LASTPIN (-7950 375) SIG_NAME GND\g
J 0
(-7940 385);
DISPLAY 0.659574 (-7940 385);
PAINT MONO (-7940 385);
DISPLAY INVISIBLE (-7940 385);
FORCEPROP 1 LAST SIZE 1B
J 0
(-7875 275);
DISPLAY 0.872340 (-7875 275);
PAINT GREEN (-7875 275);
DISPLAY INVISIBLE (-7875 275);
FORCEPROP 2 LAST CDS_LIB pure_quanta_power
J 0
(-7950 325);
DISPLAY INVISIBLE (-7950 325);
FORCEPROP 1 LAST HDL_POWER GND
J 0
(-7950 475);
DISPLAY 0.872340 (-7950 475);
PAINT GREEN (-7950 475);
DISPLAY INVISIBLE (-7950 475);
FORCEPROP 1 LAST PATH I322
J 0
(-7875 325);
DISPLAY 0.872340 (-7875 325);
PAINT AQUA (-7875 325);
DISPLAY INVISIBLE (-7875 325);
FORCEADD UNIVERSAL_POWER..1
(-8275 1600);
FORCEPROP 3 LASTPIN (-8275 1550) SIG_NAME PVDD18_S5_P1\g
J 0
(-8265 1560);
DISPLAY 0.659574 (-8265 1560);
PAINT MONO (-8265 1560);
DISPLAY INVISIBLE (-8265 1560);
FORCEPROP 1 LAST HDL_POWER PVDD18_S5_P1
J 1
(-8275 1650);
DISPLAY 0.489362 (-8275 1650);
PAINT GREEN (-8275 1650);
FORCEPROP 2 LAST CDS_LIB pure_quanta_power
J 0
(-8275 1600);
DISPLAY INVISIBLE (-8275 1600);
FORCEPROP 1 LAST PATH I323
J 0
(-8225 1625);
DISPLAY 0.872340 (-8225 1625);
PAINT AQUA (-8225 1625);
DISPLAY INVISIBLE (-8225 1625);
FORCEADD Q_RES..2
(-8275 1325);
FORCEPROP 1 LAST LOCATION R523
J 0
(-8250 1425);
DISPLAY 0.489362 (-8250 1425);
PAINT SKYBLUE (-8250 1425);
FORCEPROP 2 LAST $SEC 1
J 0
(-8225 1550);
DISPLAY 0.680851 (-8225 1550);
PAINT MONO (-8225 1550);
DISPLAY INVISIBLE (-8225 1550);
FORCEPROP 2 LAST CDS_SEC 1
J 0
(-8225 1550);
DISPLAY 1.021277 (-8225 1550);
DISPLAY INVISIBLE (-8225 1550);
FORCEPROP 1 LASTPIN (-8275 1425) $PN 1
J 0
(-8270 1387);
DISPLAY 0.489362 (-8270 1387);
FORCEPROP 1 LASTPIN (-8275 1225) $PN 2
J 0
(-8270 1235);
DISPLAY 0.489362 (-8270 1235);
FORCEPROP 1 LAST TOLERANCE 1%
J 0
(-8250 1325);
DISPLAY 0.489362 (-8250 1325);
PAINT SKYBLUE (-8250 1325);
FORCEPROP 1 LAST WATTAGE 1/16W
J 0
(-8250 1275);
DISPLAY 0.489362 (-8250 1275);
PAINT SKYBLUE (-8250 1275);
FORCEPROP 1 LAST MATERIAL CHIP
J 0
(-8250 1225);
DISPLAY 0.489362 (-8250 1225);
PAINT SKYBLUE (-8250 1225);
FORCEPROP 1 LAST VALUE 1K
J 0
(-8250 1375);
DISPLAY 0.489362 (-8250 1375);
PAINT SKYBLUE (-8250 1375);
FORCEPROP 1 LAST PACK_TYPE 0402LF
J 0
(-8250 1175);
DISPLAY 0.489362 (-8250 1175);
PAINT SKYBLUE (-8250 1175);
FORCEPROP 2 LAST CDS_LIB pure_quanta
J 0
(-8275 1325);
DISPLAY INVISIBLE (-8275 1325);
FORCEPROP 1 LAST PATH I324
J 0
(-8225 1500);
DISPLAY 0.978723 (-8225 1500);
PAINT WHITE (-8225 1500);
DISPLAY INVISIBLE (-8225 1500);
FORCEPROP 1 LAST PART_NUMBER CS21002FB06
J 0
(-8235 1200);
DISPLAY 0.617021 (-8235 1200);
PAINT SKYBLUE (-8235 1200);
DISPLAY INVISIBLE (-8235 1200);
FORCEADD Q_CAP..1
(-8275 625);
FORCEPROP 1 LAST LOCATION C230
J 0
(-8225 725);
DISPLAY 0.489362 (-8225 725);
PAINT SKYBLUE (-8225 725);
FORCEPROP 0 LAST $SEC 1
J 0
(-8225 775);
PAINT MONO (-8225 775);
DISPLAY INVISIBLE (-8225 775);
FORCEPROP 0 LAST CDS_SEC 1
J 0
(-8225 775);
PAINT MONO (-8225 775);
DISPLAY INVISIBLE (-8225 775);
FORCEPROP 1 LASTPIN (-8275 725) $PN 1
J 0
(-8265 705);
DISPLAY 0.489362 (-8265 705);
PAINT GREEN (-8265 705);
FORCEPROP 1 LASTPIN (-8275 525) $PN 2
J 0
(-8265 505);
DISPLAY 0.489362 (-8265 505);
PAINT GREEN (-8265 505);
FORCEPROP 1 LAST PACK_TYPE C0402
J 0
(-8225 475);
DISPLAY 0.489362 (-8225 475);
PAINT SKYBLUE (-8225 475);
FORCEPROP 1 LAST VOLTAGE 50V
J 0
(-8225 625);
DISPLAY 0.489362 (-8225 625);
PAINT SKYBLUE (-8225 625);
FORCEPROP 1 LAST VALUE 0.001UF
J 0
(-8225 675);
DISPLAY 0.489362 (-8225 675);
PAINT SKYBLUE (-8225 675);
FORCEPROP 1 LAST TOLERANCE 10%
J 0
(-8225 575);
DISPLAY 0.489362 (-8225 575);
PAINT SKYBLUE (-8225 575);
FORCEPROP 1 LAST MATERIAL EMPTY
J 0
(-8225 425);
DISPLAY 0.489362 (-8225 425);
PAINT RED (-8225 425);
FORCEPROP 2 LAST CDS_LIB pure_quanta
J 0
(-8275 625);
PAINT MONO (-8275 625);
DISPLAY INVISIBLE (-8275 625);
FORCEPROP 1 LAST PATH I325
J 0
(-8225 775);
DISPLAY 0.978723 (-8225 775);
PAINT WHITE (-8225 775);
DISPLAY INVISIBLE (-8225 775);
FORCEPROP 1 LAST PART_NUMBER CH30106KB19
J 0
(-8225 525);
DISPLAY 0.808511 (-8225 525);
PAINT SKYBLUE (-8225 525);
DISPLAY INVISIBLE (-8225 525);
FORCEADD OFFPAGE..2
R 2
(-8900 1125);
FORCEPROP 2 LAST $XR1 174 
J 0
(-9244 1125);
DISPLAY 0.638298 (-9244 1125);
PAINT MONO (-9244 1125);
FORCEPROP 2 LAST $XR0 54 
J 0
(-9124 1125);
DISPLAY 0.638298 (-9124 1125);
PAINT MONO (-9124 1125);
FORCEPROP 2 LAST CDS_LIB standard
J 2
(-8900 1125);
DISPLAY INVISIBLE (-8900 1125);
FORCEPROP 1 LAST OFFPAGE TRUE
J 2
(-9225 1000);
DISPLAY 0.872340 (-9225 1000);
PAINT GREEN (-9225 1000);
DISPLAY INVISIBLE (-9225 1000);
FORCEPROP 1 LAST COMMENT_BODY TRUE
J 2
(-8855 1030);
DISPLAY 0.872340 (-8855 1030);
PAINT GREEN (-8855 1030);
DISPLAY INVISIBLE (-8855 1030);
FORCEPROP 2 LAST PATH I326
J 0
(-9100 1175);
DISPLAY 0.680851 (-9100 1175);
DISPLAY INVISIBLE (-9100 1175);
FORCEADD OFFPAGE..2
R 2
(-8900 1025);
FORCEPROP 2 LAST $XR1 54 
J 0
(-9245 1025);
DISPLAY 0.638298 (-9245 1025);
PAINT MONO (-9245 1025);
FORCEPROP 2 LAST $XR0 173 
J 0
(-9155 1025);
DISPLAY 0.638298 (-9155 1025);
PAINT MONO (-9155 1025);
FORCEPROP 2 LAST CDS_LIB standard
J 0
(-8900 1025);
DISPLAY INVISIBLE (-8900 1025);
FORCEPROP 1 LAST OFFPAGE TRUE
J 2
(-9225 900);
DISPLAY 0.872340 (-9225 900);
PAINT GREEN (-9225 900);
DISPLAY INVISIBLE (-9225 900);
FORCEPROP 1 LAST COMMENT_BODY TRUE
J 2
(-8855 930);
DISPLAY 0.872340 (-8855 930);
PAINT GREEN (-8855 930);
DISPLAY INVISIBLE (-8855 930);
FORCEPROP 2 LAST PATH I327
J 0
(-9150 1075);
DISPLAY 0.680851 (-9150 1075);
DISPLAY INVISIBLE (-9150 1075);
FORCEADD OFFPAGE..2
R 2
(-8900 1075);
FORCEPROP 2 LAST $XR1 54 
J 0
(-9245 1075);
DISPLAY 0.638298 (-9245 1075);
PAINT MONO (-9245 1075);
FORCEPROP 2 LAST $XR0 174 
J 0
(-9155 1075);
DISPLAY 0.638298 (-9155 1075);
PAINT MONO (-9155 1075);
FORCEPROP 2 LAST CDS_LIB standard
J 0
(-8900 1075);
DISPLAY INVISIBLE (-8900 1075);
FORCEPROP 1 LAST OFFPAGE TRUE
J 2
(-9225 950);
DISPLAY 0.872340 (-9225 950);
PAINT GREEN (-9225 950);
DISPLAY INVISIBLE (-9225 950);
FORCEPROP 1 LAST COMMENT_BODY TRUE
J 2
(-8855 980);
DISPLAY 0.872340 (-8855 980);
PAINT GREEN (-8855 980);
DISPLAY INVISIBLE (-8855 980);
FORCEPROP 2 LAST PATH I328
J 0
(-9150 1125);
DISPLAY 0.680851 (-9150 1125);
DISPLAY INVISIBLE (-9150 1125);
FORCEADD OFFPAGE..2
R 2
(-8900 975);
FORCEPROP 2 LAST $XR1 54 
J 0
(-9245 975);
DISPLAY 0.638298 (-9245 975);
PAINT MONO (-9245 975);
FORCEPROP 2 LAST $XR0 173 
J 0
(-9155 975);
DISPLAY 0.638298 (-9155 975);
PAINT MONO (-9155 975);
FORCEPROP 2 LAST CDS_LIB standard
J 0
(-8900 975);
DISPLAY INVISIBLE (-8900 975);
FORCEPROP 1 LAST OFFPAGE TRUE
J 2
(-9225 850);
DISPLAY 0.872340 (-9225 850);
PAINT GREEN (-9225 850);
DISPLAY INVISIBLE (-9225 850);
FORCEPROP 1 LAST COMMENT_BODY TRUE
J 2
(-8855 880);
DISPLAY 0.872340 (-8855 880);
PAINT GREEN (-8855 880);
DISPLAY INVISIBLE (-8855 880);
FORCEPROP 2 LAST PATH I329
J 0
(-9150 1025);
DISPLAY 0.680851 (-9150 1025);
DISPLAY INVISIBLE (-9150 1025);
FORCEADD OFFPAGE..2
R 2
(-8900 925);
FORCEPROP 2 LAST $XR1 54 
J 0
(-9245 925);
DISPLAY 0.638298 (-9245 925);
PAINT MONO (-9245 925);
FORCEPROP 2 LAST $XR0 173 
J 0
(-9155 925);
DISPLAY 0.638298 (-9155 925);
PAINT MONO (-9155 925);
FORCEPROP 2 LAST CDS_LIB standard
J 0
(-8900 925);
DISPLAY INVISIBLE (-8900 925);
FORCEPROP 1 LAST OFFPAGE TRUE
J 2
(-9225 800);
DISPLAY 0.872340 (-9225 800);
PAINT GREEN (-9225 800);
DISPLAY INVISIBLE (-9225 800);
FORCEPROP 1 LAST COMMENT_BODY TRUE
J 2
(-8855 830);
DISPLAY 0.872340 (-8855 830);
PAINT GREEN (-8855 830);
DISPLAY INVISIBLE (-8855 830);
FORCEPROP 2 LAST PATH I330
J 0
(-9150 975);
DISPLAY 0.680851 (-9150 975);
DISPLAY INVISIBLE (-9150 975);
FORCEADD OFFPAGE..2
R 2
(-8900 875);
FORCEPROP 2 LAST $XR1 54 
J 0
(-9245 875);
DISPLAY 0.638298 (-9245 875);
PAINT MONO (-9245 875);
FORCEPROP 2 LAST $XR0 173 
J 0
(-9155 875);
DISPLAY 0.638298 (-9155 875);
PAINT MONO (-9155 875);
FORCEPROP 2 LAST CDS_LIB standard
J 0
(-8900 875);
DISPLAY INVISIBLE (-8900 875);
FORCEPROP 1 LAST OFFPAGE TRUE
J 2
(-9225 750);
DISPLAY 0.872340 (-9225 750);
PAINT GREEN (-9225 750);
DISPLAY INVISIBLE (-9225 750);
FORCEPROP 1 LAST COMMENT_BODY TRUE
J 2
(-8855 780);
DISPLAY 0.872340 (-8855 780);
PAINT GREEN (-8855 780);
DISPLAY INVISIBLE (-8855 780);
FORCEPROP 2 LAST PATH I331
J 0
(-9150 925);
DISPLAY 0.680851 (-9150 925);
DISPLAY INVISIBLE (-9150 925);
FORCEADD GND..1
(-8275 325);
FORCEPROP 3 LASTPIN (-8275 375) SIG_NAME GND\g
J 0
(-8265 385);
DISPLAY 0.659574 (-8265 385);
PAINT MONO (-8265 385);
DISPLAY INVISIBLE (-8265 385);
FORCEPROP 1 LAST SIZE 1B
J 0
(-8200 275);
DISPLAY 0.872340 (-8200 275);
PAINT GREEN (-8200 275);
DISPLAY INVISIBLE (-8200 275);
FORCEPROP 2 LAST CDS_LIB pure_quanta_power
J 0
(-8275 325);
DISPLAY INVISIBLE (-8275 325);
FORCEPROP 1 LAST HDL_POWER GND
J 0
(-8275 475);
DISPLAY 0.872340 (-8275 475);
PAINT GREEN (-8275 475);
DISPLAY INVISIBLE (-8275 475);
FORCEPROP 1 LAST PATH I332
J 0
(-8200 325);
DISPLAY 0.872340 (-8200 325);
PAINT AQUA (-8200 325);
DISPLAY INVISIBLE (-8200 325);
FORCEADD Q_RES..1
(-6775 5725);
FORCEPROP 1 LAST LOCATION PR170
J 0
(-7000 5725);
DISPLAY 0.489362 (-7000 5725);
PAINT SKYBLUE (-7000 5725);
FORCEPROP 0 LAST $SEC 1
J 0
(-6825 5800);
DISPLAY 0.680851 (-6825 5800);
PAINT MONO (-6825 5800);
DISPLAY INVISIBLE (-6825 5800);
FORCEPROP 0 LAST CDS_SEC 1
J 0
(-6825 5800);
DISPLAY 1.021277 (-6825 5800);
DISPLAY INVISIBLE (-6825 5800);
FORCEPROP 1 LASTPIN (-6875 5725) $PN 1
J 0
(-6863 5737);
DISPLAY 0.489362 (-6863 5737);
PAINT MONO (-6863 5737);
FORCEPROP 1 LASTPIN (-6675 5725) $PN 2
J 0
(-6713 5737);
DISPLAY 0.489362 (-6713 5737);
PAINT MONO (-6713 5737);
FORCEPROP 1 LAST VALUE 0
J 2
(-6600 5725);
DISPLAY 0.489362 (-6600 5725);
PAINT SKYBLUE (-6600 5725);
FORCEPROP 2 LAST CDS_LIB pure_quanta
J 0
(-6775 5725);
DISPLAY INVISIBLE (-6775 5725);
FORCEPROP 1 LAST WATTAGE 1/16W
J 0
(-6675 5675);
DISPLAY 0.489362 (-6675 5675);
PAINT SKYBLUE (-6675 5675);
DISPLAY INVISIBLE (-6675 5675);
FORCEPROP 1 LAST MATERIAL CHIP
J 0
(-7025 5650);
DISPLAY 0.489362 (-7025 5650);
PAINT SKYBLUE (-7025 5650);
DISPLAY INVISIBLE (-7025 5650);
FORCEPROP 1 LAST TOLERANCE 5%
J 0
(-6650 5750);
DISPLAY 0.489362 (-6650 5750);
PAINT SKYBLUE (-6650 5750);
DISPLAY INVISIBLE (-6650 5750);
FORCEPROP 1 LAST PACK_TYPE 0402LF
J 0
(-6675 5650);
DISPLAY 0.489362 (-6675 5650);
PAINT SKYBLUE (-6675 5650);
DISPLAY INVISIBLE (-6675 5650);
FORCEPROP 1 LAST PATH I333
J 0
(-6825 5875);
DISPLAY 0.978723 (-6825 5875);
PAINT WHITE (-6825 5875);
DISPLAY INVISIBLE (-6825 5875);
FORCEPROP 1 LAST PART_NUMBER CS00002JB13
J 0
(-7025 5675);
DISPLAY 0.489362 (-7025 5675);
PAINT SKYBLUE (-7025 5675);
DISPLAY INVISIBLE (-7025 5675);
FORCEADD Q_RES..1
(-6775 5775);
FORCEPROP 1 LAST LOCATION PR169
J 0
(-7000 5775);
DISPLAY 0.489362 (-7000 5775);
PAINT SKYBLUE (-7000 5775);
FORCEPROP 0 LAST $SEC 1
J 0
(-6825 5850);
DISPLAY 0.680851 (-6825 5850);
PAINT MONO (-6825 5850);
DISPLAY INVISIBLE (-6825 5850);
FORCEPROP 0 LAST CDS_SEC 1
J 0
(-6825 5850);
DISPLAY 1.021277 (-6825 5850);
DISPLAY INVISIBLE (-6825 5850);
FORCEPROP 1 LASTPIN (-6875 5775) $PN 1
J 0
(-6863 5787);
DISPLAY 0.489362 (-6863 5787);
PAINT MONO (-6863 5787);
FORCEPROP 1 LASTPIN (-6675 5775) $PN 2
J 0
(-6713 5787);
DISPLAY 0.489362 (-6713 5787);
PAINT MONO (-6713 5787);
FORCEPROP 1 LAST VALUE 0
J 2
(-6600 5775);
DISPLAY 0.489362 (-6600 5775);
PAINT SKYBLUE (-6600 5775);
FORCEPROP 2 LAST CDS_LIB pure_quanta
J 0
(-6775 5775);
DISPLAY INVISIBLE (-6775 5775);
FORCEPROP 1 LAST WATTAGE 1/16W
J 0
(-6675 5725);
DISPLAY 0.489362 (-6675 5725);
PAINT SKYBLUE (-6675 5725);
DISPLAY INVISIBLE (-6675 5725);
FORCEPROP 1 LAST MATERIAL CHIP
J 0
(-7025 5700);
DISPLAY 0.489362 (-7025 5700);
PAINT SKYBLUE (-7025 5700);
DISPLAY INVISIBLE (-7025 5700);
FORCEPROP 1 LAST TOLERANCE 5%
J 0
(-6650 5800);
DISPLAY 0.489362 (-6650 5800);
PAINT SKYBLUE (-6650 5800);
DISPLAY INVISIBLE (-6650 5800);
FORCEPROP 1 LAST PACK_TYPE 0402LF
J 0
(-6675 5700);
DISPLAY 0.489362 (-6675 5700);
PAINT SKYBLUE (-6675 5700);
DISPLAY INVISIBLE (-6675 5700);
FORCEPROP 1 LAST PATH I334
J 0
(-6825 5925);
DISPLAY 0.978723 (-6825 5925);
PAINT WHITE (-6825 5925);
DISPLAY INVISIBLE (-6825 5925);
FORCEPROP 1 LAST PART_NUMBER CS00002JB13
J 0
(-7025 5725);
DISPLAY 0.489362 (-7025 5725);
PAINT SKYBLUE (-7025 5725);
DISPLAY INVISIBLE (-7025 5725);
FORCEADD OFFPAGE..2
R 2
(-7875 5725);
FORCEPROP 2 LAST $XR0 210 
J 0
(-8130 5725);
DISPLAY 0.638298 (-8130 5725);
PAINT MONO (-8130 5725);
FORCEPROP 2 LAST CDS_LIB standard
J 0
(-7875 5725);
DISPLAY INVISIBLE (-7875 5725);
FORCEPROP 1 LAST OFFPAGE TRUE
J 2
(-8200 5600);
DISPLAY 0.872340 (-8200 5600);
PAINT GREEN (-8200 5600);
DISPLAY INVISIBLE (-8200 5600);
FORCEPROP 1 LAST COMMENT_BODY TRUE
J 2
(-7830 5630);
DISPLAY 0.872340 (-7830 5630);
PAINT GREEN (-7830 5630);
DISPLAY INVISIBLE (-7830 5630);
FORCEPROP 2 LAST PATH I335
J 0
(-7825 5800);
DISPLAY 0.680851 (-7825 5800);
DISPLAY INVISIBLE (-7825 5800);
FORCEADD OFFPAGE..2
R 2
(-7875 5775);
FORCEPROP 2 LAST $XR0 210 
J 0
(-8130 5775);
DISPLAY 0.638298 (-8130 5775);
PAINT MONO (-8130 5775);
FORCEPROP 2 LAST CDS_LIB standard
J 0
(-7875 5775);
DISPLAY INVISIBLE (-7875 5775);
FORCEPROP 1 LAST OFFPAGE TRUE
J 2
(-8200 5650);
DISPLAY 0.872340 (-8200 5650);
PAINT GREEN (-8200 5650);
DISPLAY INVISIBLE (-8200 5650);
FORCEPROP 1 LAST COMMENT_BODY TRUE
J 2
(-7830 5680);
DISPLAY 0.872340 (-7830 5680);
PAINT GREEN (-7830 5680);
DISPLAY INVISIBLE (-7830 5680);
FORCEPROP 2 LAST PATH I336
J 0
(-7825 5850);
DISPLAY 0.680851 (-7825 5850);
DISPLAY INVISIBLE (-7825 5850);
FORCEADD Q_RES..1
(-6775 5525);
FORCEPROP 1 LAST LOCATION PR237
J 0
(-7000 5525);
DISPLAY 0.489362 (-7000 5525);
PAINT SKYBLUE (-7000 5525);
FORCEPROP 0 LAST $SEC 1
J 0
(-6825 5625);
DISPLAY 0.680851 (-6825 5625);
PAINT MONO (-6825 5625);
DISPLAY INVISIBLE (-6825 5625);
FORCEPROP 0 LAST CDS_SEC 1
J 0
(-6825 5625);
DISPLAY 1.021277 (-6825 5625);
DISPLAY INVISIBLE (-6825 5625);
FORCEPROP 1 LASTPIN (-6875 5525) $PN 1
J 0
(-6863 5537);
DISPLAY 0.489362 (-6863 5537);
PAINT MONO (-6863 5537);
FORCEPROP 1 LASTPIN (-6675 5525) $PN 2
J 0
(-6713 5537);
DISPLAY 0.489362 (-6713 5537);
PAINT MONO (-6713 5537);
FORCEPROP 1 LAST VALUE 0
J 2
(-6600 5525);
DISPLAY 0.489362 (-6600 5525);
PAINT SKYBLUE (-6600 5525);
FORCEPROP 2 LAST CDS_LIB pure_quanta
J 0
(-6775 5525);
DISPLAY INVISIBLE (-6775 5525);
FORCEPROP 1 LAST WATTAGE 1/16W
J 2
(-6375 5625);
DISPLAY 0.489362 (-6375 5625);
PAINT SKYBLUE (-6375 5625);
DISPLAY INVISIBLE (-6375 5625);
FORCEPROP 1 LAST MATERIAL CHIP
J 0
(-6650 5625);
DISPLAY 0.489362 (-6650 5625);
PAINT SKYBLUE (-6650 5625);
DISPLAY INVISIBLE (-6650 5625);
FORCEPROP 1 LAST TOLERANCE 5%
J 0
(-6250 5575);
DISPLAY 0.489362 (-6250 5575);
PAINT SKYBLUE (-6250 5575);
DISPLAY INVISIBLE (-6250 5575);
FORCEPROP 1 LAST PACK_TYPE 0402LF
J 0
(-6175 5575);
DISPLAY 0.489362 (-6175 5575);
PAINT SKYBLUE (-6175 5575);
DISPLAY INVISIBLE (-6175 5575);
FORCEPROP 1 LAST PATH I337
J 0
(-6825 5675);
DISPLAY 0.978723 (-6825 5675);
PAINT WHITE (-6825 5675);
DISPLAY INVISIBLE (-6825 5675);
FORCEPROP 1 LAST PART_NUMBER CS00002JB13
J 0
(-6650 5575);
DISPLAY 0.489362 (-6650 5575);
PAINT SKYBLUE (-6650 5575);
DISPLAY INVISIBLE (-6650 5575);
FORCEADD Q_RES..1
(-6775 5575);
FORCEPROP 1 LAST LOCATION PR236
J 0
(-7000 5575);
DISPLAY 0.489362 (-7000 5575);
PAINT SKYBLUE (-7000 5575);
FORCEPROP 0 LAST $SEC 1
J 0
(-6375 5700);
DISPLAY 0.680851 (-6375 5700);
PAINT MONO (-6375 5700);
DISPLAY INVISIBLE (-6375 5700);
FORCEPROP 0 LAST CDS_SEC 1
J 0
(-6375 5700);
DISPLAY 1.021277 (-6375 5700);
DISPLAY INVISIBLE (-6375 5700);
FORCEPROP 1 LASTPIN (-6875 5575) $PN 1
J 0
(-6863 5587);
DISPLAY 0.489362 (-6863 5587);
PAINT MONO (-6863 5587);
FORCEPROP 1 LASTPIN (-6675 5575) $PN 2
J 0
(-6713 5587);
DISPLAY 0.489362 (-6713 5587);
PAINT MONO (-6713 5587);
FORCEPROP 1 LAST VALUE 0
J 2
(-6600 5575);
DISPLAY 0.489362 (-6600 5575);
PAINT SKYBLUE (-6600 5575);
FORCEPROP 2 LAST CDS_LIB pure_quanta
J 0
(-6775 5575);
DISPLAY INVISIBLE (-6775 5575);
FORCEPROP 1 LAST WATTAGE 1/16W
J 2
(-6375 5675);
DISPLAY 0.489362 (-6375 5675);
PAINT SKYBLUE (-6375 5675);
DISPLAY INVISIBLE (-6375 5675);
FORCEPROP 1 LAST MATERIAL CHIP
J 0
(-6650 5675);
DISPLAY 0.489362 (-6650 5675);
PAINT SKYBLUE (-6650 5675);
DISPLAY INVISIBLE (-6650 5675);
FORCEPROP 1 LAST TOLERANCE 5%
J 0
(-6250 5625);
DISPLAY 0.489362 (-6250 5625);
PAINT SKYBLUE (-6250 5625);
DISPLAY INVISIBLE (-6250 5625);
FORCEPROP 1 LAST PACK_TYPE 0402LF
J 0
(-6175 5625);
DISPLAY 0.489362 (-6175 5625);
PAINT SKYBLUE (-6175 5625);
DISPLAY INVISIBLE (-6175 5625);
FORCEPROP 1 LAST PATH I338
J 0
(-6825 5725);
DISPLAY 0.978723 (-6825 5725);
PAINT WHITE (-6825 5725);
DISPLAY INVISIBLE (-6825 5725);
FORCEPROP 1 LAST PART_NUMBER CS00002JB13
J 0
(-6650 5625);
DISPLAY 0.489362 (-6650 5625);
PAINT SKYBLUE (-6650 5625);
DISPLAY INVISIBLE (-6650 5625);
FORCEADD OFFPAGE..2
R 2
(-7875 5525);
FORCEPROP 2 LAST $XR0 217 
J 0
(-8130 5525);
DISPLAY 0.638298 (-8130 5525);
PAINT MONO (-8130 5525);
FORCEPROP 2 LAST CDS_LIB standard
J 0
(-7875 5525);
DISPLAY INVISIBLE (-7875 5525);
FORCEPROP 1 LAST OFFPAGE TRUE
J 2
(-8200 5400);
DISPLAY 0.872340 (-8200 5400);
PAINT GREEN (-8200 5400);
DISPLAY INVISIBLE (-8200 5400);
FORCEPROP 1 LAST COMMENT_BODY TRUE
J 2
(-7830 5430);
DISPLAY 0.872340 (-7830 5430);
PAINT GREEN (-7830 5430);
DISPLAY INVISIBLE (-7830 5430);
FORCEPROP 2 LAST PATH I339
J 0
(-7825 5600);
DISPLAY 0.680851 (-7825 5600);
DISPLAY INVISIBLE (-7825 5600);
FORCEADD OFFPAGE..2
R 2
(-7875 5575);
FORCEPROP 2 LAST $XR0 217 
J 0
(-8130 5575);
DISPLAY 0.638298 (-8130 5575);
PAINT MONO (-8130 5575);
FORCEPROP 2 LAST CDS_LIB standard
J 0
(-7875 5575);
DISPLAY INVISIBLE (-7875 5575);
FORCEPROP 1 LAST OFFPAGE TRUE
J 2
(-8200 5450);
DISPLAY 0.872340 (-8200 5450);
PAINT GREEN (-8200 5450);
DISPLAY INVISIBLE (-8200 5450);
FORCEPROP 1 LAST COMMENT_BODY TRUE
J 2
(-7830 5480);
DISPLAY 0.872340 (-7830 5480);
PAINT GREEN (-7830 5480);
DISPLAY INVISIBLE (-7830 5480);
FORCEPROP 2 LAST PATH I340
J 0
(-7825 5650);
DISPLAY 0.680851 (-7825 5650);
DISPLAY INVISIBLE (-7825 5650);
FORCEADD OFFPAGE..3
(-2375 4775);
FORCEPROP 2 LAST $XR2 82 
J 0
(-1981 4775);
DISPLAY 0.638298 (-1981 4775);
PAINT MONO (-1981 4775);
FORCEPROP 2 LAST $XR1 54 
J 0
(-2071 4775);
DISPLAY 0.638298 (-2071 4775);
PAINT MONO (-2071 4775);
FORCEPROP 2 LAST $XR0 27 
J 0
(-2161 4775);
DISPLAY 0.638298 (-2161 4775);
PAINT MONO (-2161 4775);
FORCEPROP 2 LAST CDS_LIB standard
J 0
(-2375 4775);
DISPLAY INVISIBLE (-2375 4775);
FORCEPROP 1 LAST OFFPAGE TRUE
J 0
(-2050 4650);
DISPLAY 0.872340 (-2050 4650);
PAINT GREEN (-2050 4650);
DISPLAY INVISIBLE (-2050 4650);
FORCEPROP 1 LAST COMMENT_BODY TRUE
J 0
(-2425 4675);
DISPLAY 0.872340 (-2425 4675);
PAINT GREEN (-2425 4675);
DISPLAY INVISIBLE (-2425 4675);
FORCEPROP 2 LAST PATH I357
J 0
(-2050 4825);
DISPLAY 0.680851 (-2050 4825);
DISPLAY INVISIBLE (-2050 4825);
FORCEADD OFFPAGE..3
(-2375 4725);
FORCEPROP 2 LAST $XR2 82 
J 0
(-1981 4725);
DISPLAY 0.638298 (-1981 4725);
PAINT MONO (-1981 4725);
FORCEPROP 2 LAST $XR1 54 
J 0
(-2071 4725);
DISPLAY 0.638298 (-2071 4725);
PAINT MONO (-2071 4725);
FORCEPROP 2 LAST $XR0 27 
J 0
(-2161 4725);
DISPLAY 0.638298 (-2161 4725);
PAINT MONO (-2161 4725);
FORCEPROP 2 LAST CDS_LIB standard
J 0
(-2375 4725);
DISPLAY INVISIBLE (-2375 4725);
FORCEPROP 1 LAST OFFPAGE TRUE
J 0
(-2050 4600);
DISPLAY 0.872340 (-2050 4600);
PAINT GREEN (-2050 4600);
DISPLAY INVISIBLE (-2050 4600);
FORCEPROP 1 LAST COMMENT_BODY TRUE
J 0
(-2425 4625);
DISPLAY 0.872340 (-2425 4625);
PAINT GREEN (-2425 4625);
DISPLAY INVISIBLE (-2425 4625);
FORCEPROP 2 LAST PATH I358
J 0
(-2050 4775);
DISPLAY 0.680851 (-2050 4775);
DISPLAY INVISIBLE (-2050 4775);
FORCEADD OFFPAGE..3
(-2375 4825);
FORCEPROP 2 LAST $XR2 82 
J 0
(-1981 4825);
DISPLAY 0.638298 (-1981 4825);
PAINT MONO (-1981 4825);
FORCEPROP 2 LAST $XR1 54 
J 0
(-2071 4825);
DISPLAY 0.638298 (-2071 4825);
PAINT MONO (-2071 4825);
FORCEPROP 2 LAST $XR0 27 
J 0
(-2161 4825);
DISPLAY 0.638298 (-2161 4825);
PAINT MONO (-2161 4825);
FORCEPROP 2 LAST CDS_LIB standard
J 0
(-2375 4825);
DISPLAY INVISIBLE (-2375 4825);
FORCEPROP 1 LAST OFFPAGE TRUE
J 0
(-2050 4700);
DISPLAY 0.872340 (-2050 4700);
PAINT GREEN (-2050 4700);
DISPLAY INVISIBLE (-2050 4700);
FORCEPROP 1 LAST COMMENT_BODY TRUE
J 0
(-2425 4725);
DISPLAY 0.872340 (-2425 4725);
PAINT GREEN (-2425 4725);
DISPLAY INVISIBLE (-2425 4725);
FORCEPROP 2 LAST PATH I359
J 0
(-2050 4875);
DISPLAY 0.680851 (-2050 4875);
DISPLAY INVISIBLE (-2050 4875);
FORCEADD OFFPAGE..3
(-2375 4675);
FORCEPROP 2 LAST $XR2 82 
J 0
(-1981 4675);
DISPLAY 0.638298 (-1981 4675);
PAINT MONO (-1981 4675);
FORCEPROP 2 LAST $XR1 54 
J 0
(-2071 4675);
DISPLAY 0.638298 (-2071 4675);
PAINT MONO (-2071 4675);
FORCEPROP 2 LAST $XR0 27 
J 0
(-2161 4675);
DISPLAY 0.638298 (-2161 4675);
PAINT MONO (-2161 4675);
FORCEPROP 2 LAST CDS_LIB standard
J 0
(-2375 4675);
DISPLAY INVISIBLE (-2375 4675);
FORCEPROP 1 LAST OFFPAGE TRUE
J 0
(-2050 4550);
DISPLAY 0.872340 (-2050 4550);
PAINT GREEN (-2050 4550);
DISPLAY INVISIBLE (-2050 4550);
FORCEPROP 1 LAST COMMENT_BODY TRUE
J 0
(-2425 4575);
DISPLAY 0.872340 (-2425 4575);
PAINT GREEN (-2425 4575);
DISPLAY INVISIBLE (-2425 4575);
FORCEPROP 2 LAST PATH I360
J 0
(-2050 4725);
DISPLAY 0.680851 (-2050 4725);
DISPLAY INVISIBLE (-2050 4725);
FORCEADD Q_RES..1
(-3100 4775);
FORCEPROP 1 LAST LOCATION R618
J 0
(-2975 4775);
DISPLAY 0.489362 (-2975 4775);
PAINT SKYBLUE (-2975 4775);
FORCEPROP 0 LAST $SEC 1
J 0
(-2975 4825);
DISPLAY 0.680851 (-2975 4825);
PAINT MONO (-2975 4825);
DISPLAY INVISIBLE (-2975 4825);
FORCEPROP 0 LAST CDS_SEC 1
J 0
(-2975 4825);
DISPLAY 0.680851 (-2975 4825);
DISPLAY INVISIBLE (-2975 4825);
FORCEPROP 1 LASTPIN (-3200 4775) $PN 1
J 0
(-3188 4787);
DISPLAY 0.489362 (-3188 4787);
PAINT MONO (-3188 4787);
FORCEPROP 1 LASTPIN (-3000 4775) $PN 2
J 0
(-3038 4787);
DISPLAY 0.489362 (-3038 4787);
PAINT MONO (-3038 4787);
FORCEPROP 1 LAST VALUE 0
J 2
(-3200 4775);
DISPLAY 0.489362 (-3200 4775);
PAINT SKYBLUE (-3200 4775);
FORCEPROP 2 LAST CDS_LIB pure_quanta
J 0
(-3100 4775);
DISPLAY INVISIBLE (-3100 4775);
FORCEPROP 1 LAST WATTAGE 1/16W
J 2
(-2700 4700);
DISPLAY 0.489362 (-2700 4700);
PAINT SKYBLUE (-2700 4700);
DISPLAY INVISIBLE (-2700 4700);
FORCEPROP 1 LAST MATERIAL CHIP
J 0
(-2675 4700);
DISPLAY 0.489362 (-2675 4700);
PAINT SKYBLUE (-2675 4700);
DISPLAY INVISIBLE (-2675 4700);
FORCEPROP 1 LAST TOLERANCE 5%
J 0
(-3125 4700);
DISPLAY 0.489362 (-3125 4700);
PAINT SKYBLUE (-3125 4700);
DISPLAY INVISIBLE (-3125 4700);
FORCEPROP 1 LAST PACK_TYPE 0402LF
J 0
(-3050 4700);
DISPLAY 0.489362 (-3050 4700);
PAINT SKYBLUE (-3050 4700);
DISPLAY INVISIBLE (-3050 4700);
FORCEPROP 1 LAST PATH I361
J 0
(-3150 4925);
DISPLAY 0.978723 (-3150 4925);
PAINT WHITE (-3150 4925);
DISPLAY INVISIBLE (-3150 4925);
FORCEPROP 1 LAST PART_NUMBER CS00002JB13
J 0
(-3075 4825);
DISPLAY 0.489362 (-3075 4825);
PAINT SKYBLUE (-3075 4825);
DISPLAY INVISIBLE (-3075 4825);
FORCEADD Q_RES..1
(-3100 4825);
FORCEPROP 1 LAST LOCATION R486
J 0
(-2975 4825);
DISPLAY 0.489362 (-2975 4825);
PAINT SKYBLUE (-2975 4825);
FORCEPROP 0 LAST $SEC 1
J 0
(-2975 4875);
DISPLAY 0.680851 (-2975 4875);
PAINT MONO (-2975 4875);
DISPLAY INVISIBLE (-2975 4875);
FORCEPROP 0 LAST CDS_SEC 1
J 0
(-2975 4875);
DISPLAY 0.680851 (-2975 4875);
DISPLAY INVISIBLE (-2975 4875);
FORCEPROP 1 LASTPIN (-3200 4825) $PN 1
J 0
(-3188 4837);
DISPLAY 0.489362 (-3188 4837);
PAINT MONO (-3188 4837);
FORCEPROP 1 LASTPIN (-3000 4825) $PN 2
J 0
(-3038 4837);
DISPLAY 0.489362 (-3038 4837);
PAINT MONO (-3038 4837);
FORCEPROP 1 LAST VALUE 0
J 2
(-3200 4825);
DISPLAY 0.489362 (-3200 4825);
PAINT SKYBLUE (-3200 4825);
FORCEPROP 2 LAST CDS_LIB pure_quanta
J 0
(-3100 4825);
DISPLAY INVISIBLE (-3100 4825);
FORCEPROP 1 LAST WATTAGE 1/16W
J 2
(-2700 4750);
DISPLAY 0.489362 (-2700 4750);
PAINT SKYBLUE (-2700 4750);
DISPLAY INVISIBLE (-2700 4750);
FORCEPROP 1 LAST MATERIAL CHIP
J 0
(-2675 4750);
DISPLAY 0.489362 (-2675 4750);
PAINT SKYBLUE (-2675 4750);
DISPLAY INVISIBLE (-2675 4750);
FORCEPROP 1 LAST TOLERANCE 5%
J 0
(-3125 4750);
DISPLAY 0.489362 (-3125 4750);
PAINT SKYBLUE (-3125 4750);
DISPLAY INVISIBLE (-3125 4750);
FORCEPROP 1 LAST PACK_TYPE 0402LF
J 0
(-3050 4750);
DISPLAY 0.489362 (-3050 4750);
PAINT SKYBLUE (-3050 4750);
DISPLAY INVISIBLE (-3050 4750);
FORCEPROP 1 LAST PATH I362
J 0
(-3150 4975);
DISPLAY 0.978723 (-3150 4975);
PAINT WHITE (-3150 4975);
DISPLAY INVISIBLE (-3150 4975);
FORCEPROP 1 LAST PART_NUMBER CS00002JB13
J 0
(-3075 4875);
DISPLAY 0.489362 (-3075 4875);
PAINT SKYBLUE (-3075 4875);
DISPLAY INVISIBLE (-3075 4875);
FORCEADD Q_RES..1
(-3100 4675);
FORCEPROP 1 LAST LOCATION R928
J 0
(-2975 4675);
DISPLAY 0.489362 (-2975 4675);
PAINT SKYBLUE (-2975 4675);
FORCEPROP 0 LAST $SEC 1
J 0
(-2975 4725);
DISPLAY 0.680851 (-2975 4725);
PAINT MONO (-2975 4725);
DISPLAY INVISIBLE (-2975 4725);
FORCEPROP 0 LAST CDS_SEC 1
J 0
(-2975 4725);
DISPLAY 0.680851 (-2975 4725);
DISPLAY INVISIBLE (-2975 4725);
FORCEPROP 1 LASTPIN (-3200 4675) $PN 1
J 0
(-3188 4687);
DISPLAY 0.489362 (-3188 4687);
PAINT MONO (-3188 4687);
FORCEPROP 1 LASTPIN (-3000 4675) $PN 2
J 0
(-3038 4687);
DISPLAY 0.489362 (-3038 4687);
PAINT MONO (-3038 4687);
FORCEPROP 1 LAST VALUE 0
J 2
(-3200 4675);
DISPLAY 0.489362 (-3200 4675);
PAINT SKYBLUE (-3200 4675);
FORCEPROP 2 LAST CDS_LIB pure_quanta
J 0
(-3100 4675);
DISPLAY INVISIBLE (-3100 4675);
FORCEPROP 1 LAST WATTAGE 1/16W
J 2
(-2700 4600);
DISPLAY 0.489362 (-2700 4600);
PAINT SKYBLUE (-2700 4600);
DISPLAY INVISIBLE (-2700 4600);
FORCEPROP 1 LAST MATERIAL CHIP
J 0
(-2675 4600);
DISPLAY 0.489362 (-2675 4600);
PAINT SKYBLUE (-2675 4600);
DISPLAY INVISIBLE (-2675 4600);
FORCEPROP 1 LAST TOLERANCE 5%
J 0
(-3125 4600);
DISPLAY 0.489362 (-3125 4600);
PAINT SKYBLUE (-3125 4600);
DISPLAY INVISIBLE (-3125 4600);
FORCEPROP 1 LAST PACK_TYPE 0402LF
J 0
(-3050 4600);
DISPLAY 0.489362 (-3050 4600);
PAINT SKYBLUE (-3050 4600);
DISPLAY INVISIBLE (-3050 4600);
FORCEPROP 1 LAST PATH I363
J 0
(-3150 4825);
DISPLAY 0.978723 (-3150 4825);
PAINT WHITE (-3150 4825);
DISPLAY INVISIBLE (-3150 4825);
FORCEPROP 1 LAST PART_NUMBER CS00002JB13
J 0
(-3075 4725);
DISPLAY 0.489362 (-3075 4725);
PAINT SKYBLUE (-3075 4725);
DISPLAY INVISIBLE (-3075 4725);
FORCEADD Q_RES..1
(-3100 4725);
FORCEPROP 1 LAST LOCATION R862
J 0
(-2975 4725);
DISPLAY 0.489362 (-2975 4725);
PAINT SKYBLUE (-2975 4725);
FORCEPROP 0 LAST $SEC 1
J 0
(-2975 4775);
DISPLAY 0.680851 (-2975 4775);
PAINT MONO (-2975 4775);
DISPLAY INVISIBLE (-2975 4775);
FORCEPROP 0 LAST CDS_SEC 1
J 0
(-2975 4775);
DISPLAY 0.680851 (-2975 4775);
DISPLAY INVISIBLE (-2975 4775);
FORCEPROP 1 LASTPIN (-3200 4725) $PN 1
J 0
(-3188 4737);
DISPLAY 0.489362 (-3188 4737);
PAINT MONO (-3188 4737);
FORCEPROP 1 LASTPIN (-3000 4725) $PN 2
J 0
(-3038 4737);
DISPLAY 0.489362 (-3038 4737);
PAINT MONO (-3038 4737);
FORCEPROP 1 LAST VALUE 0
J 2
(-3200 4725);
DISPLAY 0.489362 (-3200 4725);
PAINT SKYBLUE (-3200 4725);
FORCEPROP 2 LAST CDS_LIB pure_quanta
J 0
(-3100 4725);
DISPLAY INVISIBLE (-3100 4725);
FORCEPROP 1 LAST WATTAGE 1/16W
J 2
(-2700 4650);
DISPLAY 0.489362 (-2700 4650);
PAINT SKYBLUE (-2700 4650);
DISPLAY INVISIBLE (-2700 4650);
FORCEPROP 1 LAST MATERIAL CHIP
J 0
(-2675 4650);
DISPLAY 0.489362 (-2675 4650);
PAINT SKYBLUE (-2675 4650);
DISPLAY INVISIBLE (-2675 4650);
FORCEPROP 1 LAST TOLERANCE 5%
J 0
(-3125 4650);
DISPLAY 0.489362 (-3125 4650);
PAINT SKYBLUE (-3125 4650);
DISPLAY INVISIBLE (-3125 4650);
FORCEPROP 1 LAST PACK_TYPE 0402LF
J 0
(-3050 4650);
DISPLAY 0.489362 (-3050 4650);
PAINT SKYBLUE (-3050 4650);
DISPLAY INVISIBLE (-3050 4650);
FORCEPROP 1 LAST PATH I364
J 0
(-3150 4875);
DISPLAY 0.978723 (-3150 4875);
PAINT WHITE (-3150 4875);
DISPLAY INVISIBLE (-3150 4875);
FORCEPROP 1 LAST PART_NUMBER CS00002JB13
J 0
(-3075 4775);
DISPLAY 0.489362 (-3075 4775);
PAINT SKYBLUE (-3075 4775);
DISPLAY INVISIBLE (-3075 4775);
FORCEADD UNIVERSAL_GND..1
(-675 2300);
FORCEPROP 3 LASTPIN (-675 2350) SIG_NAME GND\g
J 0
(-665 2360);
DISPLAY 0.659574 (-665 2360);
PAINT MONO (-665 2360);
DISPLAY INVISIBLE (-665 2360);
FORCEPROP 2 LAST CDS_LIB pure_quanta_power
J 0
(-675 2300);
DISPLAY INVISIBLE (-675 2300);
FORCEPROP 1 LAST HDL_POWER GND
J 1
(-650 2225);
DISPLAY 0.872340 (-650 2225);
PAINT GREEN (-650 2225);
DISPLAY INVISIBLE (-650 2225);
FORCEPROP 1 LAST PATH I365
J 0
(-600 2300);
DISPLAY 0.872340 (-600 2300);
PAINT AQUA (-600 2300);
DISPLAY INVISIBLE (-600 2300);
FORCEADD OFFPAGE..2
R 2
(-1975 2450);
FORCEPROP 2 LAST $XR0 54 
J 0
(-2229 2450);
DISPLAY 0.638298 (-2229 2450);
PAINT MONO (-2229 2450);
FORCEPROP 2 LAST CDS_LIB standard
J 0
(-1975 2450);
DISPLAY INVISIBLE (-1975 2450);
FORCEPROP 1 LAST OFFPAGE TRUE
J 2
(-2300 2325);
DISPLAY 0.872340 (-2300 2325);
PAINT GREEN (-2300 2325);
DISPLAY INVISIBLE (-2300 2325);
FORCEPROP 1 LAST COMMENT_BODY TRUE
J 2
(-1930 2355);
DISPLAY 0.872340 (-1930 2355);
PAINT PEACH (-1930 2355);
DISPLAY INVISIBLE (-1930 2355);
FORCEPROP 2 LAST PATH I366
J 0
(-2225 2500);
DISPLAY 0.680851 (-2225 2500);
DISPLAY INVISIBLE (-2225 2500);
FORCEADD OFFPAGE..2
R 2
(-1975 2500);
FORCEPROP 2 LAST $XR0 54 
J 0
(-2229 2500);
DISPLAY 0.638298 (-2229 2500);
PAINT MONO (-2229 2500);
FORCEPROP 2 LAST CDS_LIB standard
J 0
(-1975 2500);
DISPLAY INVISIBLE (-1975 2500);
FORCEPROP 1 LAST OFFPAGE TRUE
J 2
(-2300 2375);
DISPLAY 0.872340 (-2300 2375);
PAINT GREEN (-2300 2375);
DISPLAY INVISIBLE (-2300 2375);
FORCEPROP 1 LAST COMMENT_BODY TRUE
J 2
(-1930 2405);
DISPLAY 0.872340 (-1930 2405);
PAINT PEACH (-1930 2405);
DISPLAY INVISIBLE (-1930 2405);
FORCEPROP 2 LAST PATH I367
J 0
(-2225 2550);
DISPLAY 0.680851 (-2225 2550);
DISPLAY INVISIBLE (-2225 2550);
FORCEADD OFFPAGE..2
R 2
(-1975 2600);
FORCEPROP 2 LAST $XR0 54 
J 0
(-2229 2600);
DISPLAY 0.638298 (-2229 2600);
PAINT MONO (-2229 2600);
FORCEPROP 2 LAST CDS_LIB standard
J 0
(-1975 2600);
DISPLAY INVISIBLE (-1975 2600);
FORCEPROP 1 LAST OFFPAGE TRUE
J 2
(-2300 2475);
DISPLAY 0.872340 (-2300 2475);
PAINT GREEN (-2300 2475);
DISPLAY INVISIBLE (-2300 2475);
FORCEPROP 1 LAST COMMENT_BODY TRUE
J 2
(-1930 2505);
DISPLAY 0.872340 (-1930 2505);
PAINT PEACH (-1930 2505);
DISPLAY INVISIBLE (-1930 2505);
FORCEPROP 2 LAST PATH I368
J 0
(-2225 2650);
DISPLAY 0.680851 (-2225 2650);
DISPLAY INVISIBLE (-2225 2650);
FORCEADD OFFPAGE..2
R 2
(-1975 2550);
FORCEPROP 2 LAST $XR0 54 
J 0
(-2229 2550);
DISPLAY 0.638298 (-2229 2550);
PAINT MONO (-2229 2550);
FORCEPROP 2 LAST CDS_LIB standard
J 0
(-1975 2550);
DISPLAY INVISIBLE (-1975 2550);
FORCEPROP 1 LAST OFFPAGE TRUE
J 2
(-2300 2425);
DISPLAY 0.872340 (-2300 2425);
PAINT GREEN (-2300 2425);
DISPLAY INVISIBLE (-2300 2425);
FORCEPROP 1 LAST COMMENT_BODY TRUE
J 2
(-1930 2455);
DISPLAY 0.872340 (-1930 2455);
PAINT PEACH (-1930 2455);
DISPLAY INVISIBLE (-1930 2455);
FORCEPROP 2 LAST PATH I369
J 0
(-2225 2600);
DISPLAY 0.680851 (-2225 2600);
DISPLAY INVISIBLE (-2225 2600);
FORCEADD UNIVERSAL_GND..1
(-150 3350);
FORCEPROP 3 LASTPIN (-150 3400) SIG_NAME GND\g
J 0
(-140 3410);
DISPLAY 0.659574 (-140 3410);
PAINT MONO (-140 3410);
DISPLAY INVISIBLE (-140 3410);
FORCEPROP 2 LAST CDS_LIB pure_quanta_power
J 0
(-150 3350);
DISPLAY INVISIBLE (-150 3350);
FORCEPROP 1 LAST HDL_POWER GND
J 1
(-125 3275);
DISPLAY 0.872340 (-125 3275);
PAINT GREEN (-125 3275);
DISPLAY INVISIBLE (-125 3275);
FORCEPROP 1 LAST PATH I370
J 0
(-75 3350);
DISPLAY 0.872340 (-75 3350);
PAINT AQUA (-75 3350);
DISPLAY INVISIBLE (-75 3350);
FORCEADD Q_RES..1
(-1425 3650);
FORCEPROP 1 LAST LOCATION R929
J 0
(-1325 3650);
DISPLAY 0.489362 (-1325 3650);
PAINT SKYBLUE (-1325 3650);
FORCEPROP 0 LAST $SEC 1
J 0
(-1325 3700);
DISPLAY 0.680851 (-1325 3700);
PAINT MONO (-1325 3700);
DISPLAY INVISIBLE (-1325 3700);
FORCEPROP 0 LAST CDS_SEC 1
J 0
(-1325 3700);
DISPLAY 0.680851 (-1325 3700);
DISPLAY INVISIBLE (-1325 3700);
FORCEPROP 1 LASTPIN (-1525 3650) $PN 1
J 0
(-1513 3662);
DISPLAY 0.489362 (-1513 3662);
PAINT MONO (-1513 3662);
FORCEPROP 1 LASTPIN (-1325 3650) $PN 2
J 0
(-1363 3662);
DISPLAY 0.489362 (-1363 3662);
PAINT MONO (-1363 3662);
FORCEPROP 1 LAST VALUE 0
J 2
(-1525 3650);
DISPLAY 0.489362 (-1525 3650);
PAINT SKYBLUE (-1525 3650);
FORCEPROP 2 LAST CDS_LIB pure_quanta
J 0
(-1425 3650);
DISPLAY INVISIBLE (-1425 3650);
FORCEPROP 1 LAST WATTAGE 1/16W
J 2
(-1025 3575);
DISPLAY 0.489362 (-1025 3575);
PAINT SKYBLUE (-1025 3575);
DISPLAY INVISIBLE (-1025 3575);
FORCEPROP 1 LAST MATERIAL CHIP
J 0
(-1000 3575);
DISPLAY 0.489362 (-1000 3575);
PAINT SKYBLUE (-1000 3575);
DISPLAY INVISIBLE (-1000 3575);
FORCEPROP 1 LAST TOLERANCE 5%
J 0
(-1450 3575);
DISPLAY 0.489362 (-1450 3575);
PAINT SKYBLUE (-1450 3575);
DISPLAY INVISIBLE (-1450 3575);
FORCEPROP 1 LAST PACK_TYPE 0402LF
J 0
(-1375 3575);
DISPLAY 0.489362 (-1375 3575);
PAINT SKYBLUE (-1375 3575);
DISPLAY INVISIBLE (-1375 3575);
FORCEPROP 1 LAST PATH I371
J 0
(-1475 3800);
DISPLAY 0.978723 (-1475 3800);
PAINT WHITE (-1475 3800);
DISPLAY INVISIBLE (-1475 3800);
FORCEPROP 1 LAST PART_NUMBER CS00002JB13
J 0
(-1400 3700);
DISPLAY 0.489362 (-1400 3700);
PAINT SKYBLUE (-1400 3700);
DISPLAY INVISIBLE (-1400 3700);
FORCEADD Q_RES..1
(-1425 3600);
FORCEPROP 1 LAST LOCATION R930
J 0
(-1325 3600);
DISPLAY 0.489362 (-1325 3600);
PAINT SKYBLUE (-1325 3600);
FORCEPROP 0 LAST $SEC 1
J 0
(-1325 3650);
DISPLAY 0.680851 (-1325 3650);
PAINT MONO (-1325 3650);
DISPLAY INVISIBLE (-1325 3650);
FORCEPROP 0 LAST CDS_SEC 1
J 0
(-1325 3650);
DISPLAY 0.680851 (-1325 3650);
DISPLAY INVISIBLE (-1325 3650);
FORCEPROP 1 LASTPIN (-1525 3600) $PN 1
J 0
(-1513 3612);
DISPLAY 0.489362 (-1513 3612);
PAINT MONO (-1513 3612);
FORCEPROP 1 LASTPIN (-1325 3600) $PN 2
J 0
(-1363 3612);
DISPLAY 0.489362 (-1363 3612);
PAINT MONO (-1363 3612);
FORCEPROP 1 LAST VALUE 0
J 2
(-1525 3600);
DISPLAY 0.489362 (-1525 3600);
PAINT SKYBLUE (-1525 3600);
FORCEPROP 2 LAST CDS_LIB pure_quanta
J 0
(-1425 3600);
DISPLAY INVISIBLE (-1425 3600);
FORCEPROP 1 LAST WATTAGE 1/16W
J 2
(-1025 3525);
DISPLAY 0.489362 (-1025 3525);
PAINT SKYBLUE (-1025 3525);
DISPLAY INVISIBLE (-1025 3525);
FORCEPROP 1 LAST MATERIAL CHIP
J 0
(-1000 3525);
DISPLAY 0.489362 (-1000 3525);
PAINT SKYBLUE (-1000 3525);
DISPLAY INVISIBLE (-1000 3525);
FORCEPROP 1 LAST TOLERANCE 5%
J 0
(-1450 3525);
DISPLAY 0.489362 (-1450 3525);
PAINT SKYBLUE (-1450 3525);
DISPLAY INVISIBLE (-1450 3525);
FORCEPROP 1 LAST PACK_TYPE 0402LF
J 0
(-1375 3525);
DISPLAY 0.489362 (-1375 3525);
PAINT SKYBLUE (-1375 3525);
DISPLAY INVISIBLE (-1375 3525);
FORCEPROP 1 LAST PATH I372
J 0
(-1475 3750);
DISPLAY 0.978723 (-1475 3750);
PAINT WHITE (-1475 3750);
DISPLAY INVISIBLE (-1475 3750);
FORCEPROP 1 LAST PART_NUMBER CS00002JB13
J 0
(-1400 3650);
DISPLAY 0.489362 (-1400 3650);
PAINT SKYBLUE (-1400 3650);
DISPLAY INVISIBLE (-1400 3650);
FORCEADD Q_RES..1
(-1425 3500);
FORCEPROP 1 LAST LOCATION R932
J 0
(-1325 3500);
DISPLAY 0.489362 (-1325 3500);
PAINT SKYBLUE (-1325 3500);
FORCEPROP 0 LAST $SEC 1
J 0
(-1325 3550);
DISPLAY 0.680851 (-1325 3550);
PAINT MONO (-1325 3550);
DISPLAY INVISIBLE (-1325 3550);
FORCEPROP 0 LAST CDS_SEC 1
J 0
(-1325 3550);
DISPLAY 0.680851 (-1325 3550);
DISPLAY INVISIBLE (-1325 3550);
FORCEPROP 1 LASTPIN (-1525 3500) $PN 1
J 0
(-1513 3512);
DISPLAY 0.489362 (-1513 3512);
PAINT MONO (-1513 3512);
FORCEPROP 1 LASTPIN (-1325 3500) $PN 2
J 0
(-1363 3512);
DISPLAY 0.489362 (-1363 3512);
PAINT MONO (-1363 3512);
FORCEPROP 1 LAST VALUE 0
J 2
(-1525 3500);
DISPLAY 0.489362 (-1525 3500);
PAINT SKYBLUE (-1525 3500);
FORCEPROP 2 LAST CDS_LIB pure_quanta
J 0
(-1425 3500);
DISPLAY INVISIBLE (-1425 3500);
FORCEPROP 1 LAST WATTAGE 1/16W
J 2
(-1025 3425);
DISPLAY 0.489362 (-1025 3425);
PAINT SKYBLUE (-1025 3425);
DISPLAY INVISIBLE (-1025 3425);
FORCEPROP 1 LAST MATERIAL CHIP
J 0
(-1000 3425);
DISPLAY 0.489362 (-1000 3425);
PAINT SKYBLUE (-1000 3425);
DISPLAY INVISIBLE (-1000 3425);
FORCEPROP 1 LAST TOLERANCE 5%
J 0
(-1450 3425);
DISPLAY 0.489362 (-1450 3425);
PAINT SKYBLUE (-1450 3425);
DISPLAY INVISIBLE (-1450 3425);
FORCEPROP 1 LAST PACK_TYPE 0402LF
J 0
(-1375 3425);
DISPLAY 0.489362 (-1375 3425);
PAINT SKYBLUE (-1375 3425);
DISPLAY INVISIBLE (-1375 3425);
FORCEPROP 1 LAST PATH I373
J 0
(-1475 3650);
DISPLAY 0.978723 (-1475 3650);
PAINT WHITE (-1475 3650);
DISPLAY INVISIBLE (-1475 3650);
FORCEPROP 1 LAST PART_NUMBER CS00002JB13
J 0
(-1400 3550);
DISPLAY 0.489362 (-1400 3550);
PAINT SKYBLUE (-1400 3550);
DISPLAY INVISIBLE (-1400 3550);
FORCEADD Q_RES..1
(-1425 3550);
FORCEPROP 1 LAST LOCATION R931
J 0
(-1325 3550);
DISPLAY 0.489362 (-1325 3550);
PAINT SKYBLUE (-1325 3550);
FORCEPROP 0 LAST $SEC 1
J 0
(-1325 3600);
DISPLAY 0.680851 (-1325 3600);
PAINT MONO (-1325 3600);
DISPLAY INVISIBLE (-1325 3600);
FORCEPROP 0 LAST CDS_SEC 1
J 0
(-1325 3600);
DISPLAY 0.680851 (-1325 3600);
DISPLAY INVISIBLE (-1325 3600);
FORCEPROP 1 LASTPIN (-1525 3550) $PN 1
J 0
(-1513 3562);
DISPLAY 0.489362 (-1513 3562);
PAINT MONO (-1513 3562);
FORCEPROP 1 LASTPIN (-1325 3550) $PN 2
J 0
(-1363 3562);
DISPLAY 0.489362 (-1363 3562);
PAINT MONO (-1363 3562);
FORCEPROP 1 LAST VALUE 0
J 2
(-1525 3550);
DISPLAY 0.489362 (-1525 3550);
PAINT SKYBLUE (-1525 3550);
FORCEPROP 2 LAST CDS_LIB pure_quanta
J 0
(-1425 3550);
DISPLAY INVISIBLE (-1425 3550);
FORCEPROP 1 LAST WATTAGE 1/16W
J 2
(-1025 3475);
DISPLAY 0.489362 (-1025 3475);
PAINT SKYBLUE (-1025 3475);
DISPLAY INVISIBLE (-1025 3475);
FORCEPROP 1 LAST MATERIAL CHIP
J 0
(-1000 3475);
DISPLAY 0.489362 (-1000 3475);
PAINT SKYBLUE (-1000 3475);
DISPLAY INVISIBLE (-1000 3475);
FORCEPROP 1 LAST TOLERANCE 5%
J 0
(-1450 3475);
DISPLAY 0.489362 (-1450 3475);
PAINT SKYBLUE (-1450 3475);
DISPLAY INVISIBLE (-1450 3475);
FORCEPROP 1 LAST PACK_TYPE 0402LF
J 0
(-1375 3475);
DISPLAY 0.489362 (-1375 3475);
PAINT SKYBLUE (-1375 3475);
DISPLAY INVISIBLE (-1375 3475);
FORCEPROP 1 LAST PATH I374
J 0
(-1475 3700);
DISPLAY 0.978723 (-1475 3700);
PAINT WHITE (-1475 3700);
DISPLAY INVISIBLE (-1475 3700);
FORCEPROP 1 LAST PART_NUMBER CS00002JB13
J 0
(-1400 3600);
DISPLAY 0.489362 (-1400 3600);
PAINT SKYBLUE (-1400 3600);
DISPLAY INVISIBLE (-1400 3600);
FORCEADD OFFPAGE..2
R 2
(-2025 3650);
FORCEPROP 2 LAST $XR2 82 
J 0
(-2429 3650);
DISPLAY 0.638298 (-2429 3650);
PAINT MONO (-2429 3650);
FORCEPROP 2 LAST $XR1 54 
J 0
(-2339 3650);
DISPLAY 0.638298 (-2339 3650);
PAINT MONO (-2339 3650);
FORCEPROP 2 LAST $XR0 27 
J 0
(-2249 3650);
DISPLAY 0.638298 (-2249 3650);
PAINT MONO (-2249 3650);
FORCEPROP 2 LAST CDS_LIB standard
J 0
(-2025 3650);
DISPLAY INVISIBLE (-2025 3650);
FORCEPROP 1 LAST OFFPAGE TRUE
J 2
(-2350 3525);
DISPLAY 0.872340 (-2350 3525);
PAINT GREEN (-2350 3525);
DISPLAY INVISIBLE (-2350 3525);
FORCEPROP 1 LAST COMMENT_BODY TRUE
J 2
(-1980 3555);
DISPLAY 0.872340 (-1980 3555);
PAINT PEACH (-1980 3555);
DISPLAY INVISIBLE (-1980 3555);
FORCEPROP 2 LAST PATH I375
J 0
(-2275 3700);
DISPLAY 0.680851 (-2275 3700);
DISPLAY INVISIBLE (-2275 3700);
FORCEADD OFFPAGE..2
R 2
(-2025 3600);
FORCEPROP 2 LAST $XR2 82 
J 0
(-2429 3600);
DISPLAY 0.638298 (-2429 3600);
PAINT MONO (-2429 3600);
FORCEPROP 2 LAST $XR1 54 
J 0
(-2339 3600);
DISPLAY 0.638298 (-2339 3600);
PAINT MONO (-2339 3600);
FORCEPROP 2 LAST $XR0 27 
J 0
(-2249 3600);
DISPLAY 0.638298 (-2249 3600);
PAINT MONO (-2249 3600);
FORCEPROP 2 LAST CDS_LIB standard
J 0
(-2025 3600);
DISPLAY INVISIBLE (-2025 3600);
FORCEPROP 1 LAST OFFPAGE TRUE
J 2
(-2350 3475);
DISPLAY 0.872340 (-2350 3475);
PAINT GREEN (-2350 3475);
DISPLAY INVISIBLE (-2350 3475);
FORCEPROP 1 LAST COMMENT_BODY TRUE
J 2
(-1980 3505);
DISPLAY 0.872340 (-1980 3505);
PAINT PEACH (-1980 3505);
DISPLAY INVISIBLE (-1980 3505);
FORCEPROP 2 LAST PATH I376
J 0
(-2275 3650);
DISPLAY 0.680851 (-2275 3650);
DISPLAY INVISIBLE (-2275 3650);
FORCEADD OFFPAGE..2
R 2
(-2025 3550);
FORCEPROP 2 LAST $XR2 82 
J 0
(-2429 3550);
DISPLAY 0.638298 (-2429 3550);
PAINT MONO (-2429 3550);
FORCEPROP 2 LAST $XR1 54 
J 0
(-2339 3550);
DISPLAY 0.638298 (-2339 3550);
PAINT MONO (-2339 3550);
FORCEPROP 2 LAST $XR0 27 
J 0
(-2249 3550);
DISPLAY 0.638298 (-2249 3550);
PAINT MONO (-2249 3550);
FORCEPROP 2 LAST CDS_LIB standard
J 0
(-2025 3550);
DISPLAY INVISIBLE (-2025 3550);
FORCEPROP 1 LAST OFFPAGE TRUE
J 2
(-2350 3425);
DISPLAY 0.872340 (-2350 3425);
PAINT GREEN (-2350 3425);
DISPLAY INVISIBLE (-2350 3425);
FORCEPROP 1 LAST COMMENT_BODY TRUE
J 2
(-1980 3455);
DISPLAY 0.872340 (-1980 3455);
PAINT PEACH (-1980 3455);
DISPLAY INVISIBLE (-1980 3455);
FORCEPROP 2 LAST PATH I377
J 0
(-2275 3600);
DISPLAY 0.680851 (-2275 3600);
DISPLAY INVISIBLE (-2275 3600);
FORCEADD OFFPAGE..2
R 2
(-2025 3500);
FORCEPROP 2 LAST $XR2 82 
J 0
(-2429 3500);
DISPLAY 0.638298 (-2429 3500);
PAINT MONO (-2429 3500);
FORCEPROP 2 LAST $XR1 54 
J 0
(-2339 3500);
DISPLAY 0.638298 (-2339 3500);
PAINT MONO (-2339 3500);
FORCEPROP 2 LAST $XR0 27 
J 0
(-2249 3500);
DISPLAY 0.638298 (-2249 3500);
PAINT MONO (-2249 3500);
FORCEPROP 2 LAST CDS_LIB standard
J 0
(-2025 3500);
DISPLAY INVISIBLE (-2025 3500);
FORCEPROP 1 LAST OFFPAGE TRUE
J 2
(-2350 3375);
DISPLAY 0.872340 (-2350 3375);
PAINT GREEN (-2350 3375);
DISPLAY INVISIBLE (-2350 3375);
FORCEPROP 1 LAST COMMENT_BODY TRUE
J 2
(-1980 3405);
DISPLAY 0.872340 (-1980 3405);
PAINT PEACH (-1980 3405);
DISPLAY INVISIBLE (-1980 3405);
FORCEPROP 2 LAST PATH I378
J 0
(-2275 3550);
DISPLAY 0.680851 (-2275 3550);
DISPLAY INVISIBLE (-2275 3550);
FORCEADD OFFPAGE..2
(-7750 3325);
FORCEPROP 2 LAST $XR1 82 
J 0
(-7471 3325);
DISPLAY 0.638298 (-7471 3325);
PAINT MONO (-7471 3325);
FORCEPROP 2 LAST $XR0 54 
J 0
(-7561 3325);
DISPLAY 0.638298 (-7561 3325);
PAINT MONO (-7561 3325);
FORCEPROP 2 LAST CDS_LIB standard
J 0
(-7750 3325);
DISPLAY INVISIBLE (-7750 3325);
FORCEPROP 1 LAST OFFPAGE TRUE
J 0
(-7425 3200);
DISPLAY 0.872340 (-7425 3200);
PAINT GREEN (-7425 3200);
DISPLAY INVISIBLE (-7425 3200);
FORCEPROP 1 LAST COMMENT_BODY TRUE
J 0
(-7795 3230);
DISPLAY 0.872340 (-7795 3230);
PAINT PEACH (-7795 3230);
DISPLAY INVISIBLE (-7795 3230);
FORCEPROP 2 LAST PATH I379
J 0
(-7450 3375);
DISPLAY 0.680851 (-7450 3375);
DISPLAY INVISIBLE (-7450 3375);
FORCEADD OFFPAGE..2
(-7750 3275);
FORCEPROP 2 LAST $XR1 82 
J 0
(-7471 3275);
DISPLAY 0.638298 (-7471 3275);
PAINT MONO (-7471 3275);
FORCEPROP 2 LAST $XR0 54 
J 0
(-7561 3275);
DISPLAY 0.638298 (-7561 3275);
PAINT MONO (-7561 3275);
FORCEPROP 2 LAST CDS_LIB standard
J 0
(-7750 3275);
DISPLAY INVISIBLE (-7750 3275);
FORCEPROP 1 LAST OFFPAGE TRUE
J 0
(-7425 3150);
DISPLAY 0.872340 (-7425 3150);
PAINT GREEN (-7425 3150);
DISPLAY INVISIBLE (-7425 3150);
FORCEPROP 1 LAST COMMENT_BODY TRUE
J 0
(-7795 3180);
DISPLAY 0.872340 (-7795 3180);
PAINT PEACH (-7795 3180);
DISPLAY INVISIBLE (-7795 3180);
FORCEPROP 2 LAST PATH I380
J 0
(-7450 3325);
DISPLAY 0.680851 (-7450 3325);
DISPLAY INVISIBLE (-7450 3325);
FORCEADD OFFPAGE..2
(-7750 3225);
FORCEPROP 2 LAST $XR1 82 
J 0
(-7471 3225);
DISPLAY 0.638298 (-7471 3225);
PAINT MONO (-7471 3225);
FORCEPROP 2 LAST $XR0 54 
J 0
(-7561 3225);
DISPLAY 0.638298 (-7561 3225);
PAINT MONO (-7561 3225);
FORCEPROP 2 LAST CDS_LIB standard
J 0
(-7750 3225);
DISPLAY INVISIBLE (-7750 3225);
FORCEPROP 1 LAST OFFPAGE TRUE
J 0
(-7425 3100);
DISPLAY 0.872340 (-7425 3100);
PAINT GREEN (-7425 3100);
DISPLAY INVISIBLE (-7425 3100);
FORCEPROP 1 LAST COMMENT_BODY TRUE
J 0
(-7795 3130);
DISPLAY 0.872340 (-7795 3130);
PAINT PEACH (-7795 3130);
DISPLAY INVISIBLE (-7795 3130);
FORCEPROP 2 LAST PATH I381
J 0
(-7450 3275);
DISPLAY 0.680851 (-7450 3275);
DISPLAY INVISIBLE (-7450 3275);
FORCEADD OFFPAGE..2
(-7750 3175);
FORCEPROP 2 LAST $XR1 82 
J 0
(-7471 3175);
DISPLAY 0.638298 (-7471 3175);
PAINT MONO (-7471 3175);
FORCEPROP 2 LAST $XR0 54 
J 0
(-7561 3175);
DISPLAY 0.638298 (-7561 3175);
PAINT MONO (-7561 3175);
FORCEPROP 2 LAST CDS_LIB standard
J 0
(-7750 3175);
DISPLAY INVISIBLE (-7750 3175);
FORCEPROP 1 LAST OFFPAGE TRUE
J 0
(-7425 3050);
DISPLAY 0.872340 (-7425 3050);
PAINT GREEN (-7425 3050);
DISPLAY INVISIBLE (-7425 3050);
FORCEPROP 1 LAST COMMENT_BODY TRUE
J 0
(-7795 3080);
DISPLAY 0.872340 (-7795 3080);
PAINT PEACH (-7795 3080);
DISPLAY INVISIBLE (-7795 3080);
FORCEPROP 2 LAST PATH I382
J 0
(-7450 3225);
DISPLAY 0.680851 (-7450 3225);
DISPLAY INVISIBLE (-7450 3225);
FORCEADD OFFPAGE..2
(-7750 3125);
FORCEPROP 2 LAST $XR1 82 
J 0
(-7471 3125);
DISPLAY 0.638298 (-7471 3125);
PAINT MONO (-7471 3125);
FORCEPROP 2 LAST $XR0 54 
J 0
(-7561 3125);
DISPLAY 0.638298 (-7561 3125);
PAINT MONO (-7561 3125);
FORCEPROP 2 LAST CDS_LIB standard
J 0
(-7750 3125);
DISPLAY INVISIBLE (-7750 3125);
FORCEPROP 1 LAST OFFPAGE TRUE
J 0
(-7425 3000);
DISPLAY 0.872340 (-7425 3000);
PAINT GREEN (-7425 3000);
DISPLAY INVISIBLE (-7425 3000);
FORCEPROP 1 LAST COMMENT_BODY TRUE
J 0
(-7795 3030);
DISPLAY 0.872340 (-7795 3030);
PAINT PEACH (-7795 3030);
DISPLAY INVISIBLE (-7795 3030);
FORCEPROP 2 LAST PATH I384
J 0
(-7450 3175);
DISPLAY 0.680851 (-7450 3175);
DISPLAY INVISIBLE (-7450 3175);
FORCEADD OFFPAGE..2
(-7750 3075);
FORCEPROP 2 LAST $XR1 82 
J 0
(-7471 3075);
DISPLAY 0.638298 (-7471 3075);
PAINT MONO (-7471 3075);
FORCEPROP 2 LAST $XR0 54 
J 0
(-7561 3075);
DISPLAY 0.638298 (-7561 3075);
PAINT MONO (-7561 3075);
FORCEPROP 2 LAST CDS_LIB standard
J 0
(-7750 3075);
DISPLAY INVISIBLE (-7750 3075);
FORCEPROP 1 LAST OFFPAGE TRUE
J 0
(-7425 2950);
DISPLAY 0.872340 (-7425 2950);
PAINT GREEN (-7425 2950);
DISPLAY INVISIBLE (-7425 2950);
FORCEPROP 1 LAST COMMENT_BODY TRUE
J 0
(-7795 2980);
DISPLAY 0.872340 (-7795 2980);
PAINT PEACH (-7795 2980);
DISPLAY INVISIBLE (-7795 2980);
FORCEPROP 2 LAST PATH I385
J 0
(-7450 3125);
DISPLAY 0.680851 (-7450 3125);
DISPLAY INVISIBLE (-7450 3125);
FORCEADD OFFPAGE..2
(-7750 3025);
FORCEPROP 2 LAST $XR1 82 
J 0
(-7471 3025);
DISPLAY 0.638298 (-7471 3025);
PAINT MONO (-7471 3025);
FORCEPROP 2 LAST $XR0 54 
J 0
(-7561 3025);
DISPLAY 0.638298 (-7561 3025);
PAINT MONO (-7561 3025);
FORCEPROP 2 LAST CDS_LIB standard
J 0
(-7750 3025);
DISPLAY INVISIBLE (-7750 3025);
FORCEPROP 1 LAST OFFPAGE TRUE
J 0
(-7425 2900);
DISPLAY 0.872340 (-7425 2900);
PAINT GREEN (-7425 2900);
DISPLAY INVISIBLE (-7425 2900);
FORCEPROP 1 LAST COMMENT_BODY TRUE
J 0
(-7795 2930);
DISPLAY 0.872340 (-7795 2930);
PAINT PEACH (-7795 2930);
DISPLAY INVISIBLE (-7795 2930);
FORCEPROP 2 LAST PATH I386
J 0
(-7450 3075);
DISPLAY 0.680851 (-7450 3075);
DISPLAY INVISIBLE (-7450 3075);
FORCEADD Q_RES..1
(-8750 3275);
FORCEPROP 1 LAST LOCATION R517
J 2
(-8925 3275);
DISPLAY 0.489362 (-8925 3275);
PAINT SKYBLUE (-8925 3275);
FORCEPROP 0 LAST $SEC 1
J 0
(-8625 3300);
DISPLAY 0.680851 (-8625 3300);
PAINT MONO (-8625 3300);
DISPLAY INVISIBLE (-8625 3300);
FORCEPROP 0 LAST CDS_SEC 1
J 0
(-8625 3300);
DISPLAY 0.680851 (-8625 3300);
DISPLAY INVISIBLE (-8625 3300);
FORCEPROP 1 LASTPIN (-8850 3275) $PN 1
J 0
(-8838 3287);
DISPLAY 0.489362 (-8838 3287);
PAINT MONO (-8838 3287);
FORCEPROP 1 LASTPIN (-8650 3275) $PN 2
J 0
(-8688 3287);
DISPLAY 0.489362 (-8688 3287);
PAINT MONO (-8688 3287);
FORCEPROP 1 LAST VALUE 2.2K
J 0
(-8625 3275);
DISPLAY 0.489362 (-8625 3275);
PAINT SKYBLUE (-8625 3275);
FORCEPROP 1 LAST PACK_TYPE 0402LF
J 0
(-8500 3125);
DISPLAY 0.510638 (-8500 3125);
PAINT SKYBLUE (-8500 3125);
DISPLAY INVISIBLE (-8500 3125);
FORCEPROP 1 LAST TOLERANCE 5%
J 0
(-8625 3275);
DISPLAY 0.510638 (-8625 3275);
PAINT SKYBLUE (-8625 3275);
DISPLAY INVISIBLE (-8625 3275);
FORCEPROP 1 LAST MATERIAL CHIP
J 0
(-8650 3250);
DISPLAY 0.489362 (-8650 3250);
PAINT SKYBLUE (-8650 3250);
DISPLAY INVISIBLE (-8650 3250);
FORCEPROP 1 LAST WATTAGE 1/16W
J 2
(-8775 3125);
DISPLAY 0.510638 (-8775 3125);
PAINT SKYBLUE (-8775 3125);
DISPLAY INVISIBLE (-8775 3125);
FORCEPROP 2 LAST CDS_LIB pure_quanta
J 0
(-8750 3275);
DISPLAY INVISIBLE (-8750 3275);
FORCEPROP 1 LAST PATH I387
J 0
(-8800 3425);
DISPLAY 0.978723 (-8800 3425);
PAINT WHITE (-8800 3425);
DISPLAY INVISIBLE (-8800 3425);
FORCEPROP 1 LAST PART_NUMBER CS22202JB07
J 0
(-8800 3375);
DISPLAY 0.510638 (-8800 3375);
PAINT SKYBLUE (-8800 3375);
DISPLAY INVISIBLE (-8800 3375);
FORCEADD Q_RES..1
(-8750 3325);
FORCEPROP 1 LAST LOCATION R522
J 2
(-8925 3325);
DISPLAY 0.489362 (-8925 3325);
PAINT SKYBLUE (-8925 3325);
FORCEPROP 0 LAST $SEC 1
J 0
(-8625 3350);
DISPLAY 0.680851 (-8625 3350);
PAINT MONO (-8625 3350);
DISPLAY INVISIBLE (-8625 3350);
FORCEPROP 0 LAST CDS_SEC 1
J 0
(-8625 3350);
DISPLAY 0.680851 (-8625 3350);
DISPLAY INVISIBLE (-8625 3350);
FORCEPROP 1 LASTPIN (-8850 3325) $PN 1
J 0
(-8838 3337);
DISPLAY 0.489362 (-8838 3337);
PAINT MONO (-8838 3337);
FORCEPROP 1 LASTPIN (-8650 3325) $PN 2
J 0
(-8688 3337);
DISPLAY 0.489362 (-8688 3337);
PAINT MONO (-8688 3337);
FORCEPROP 1 LAST VALUE 2.2K
J 0
(-8625 3325);
DISPLAY 0.489362 (-8625 3325);
PAINT SKYBLUE (-8625 3325);
FORCEPROP 1 LAST PACK_TYPE 0402LF
J 0
(-8500 3175);
DISPLAY 0.510638 (-8500 3175);
PAINT SKYBLUE (-8500 3175);
DISPLAY INVISIBLE (-8500 3175);
FORCEPROP 1 LAST TOLERANCE 5%
J 0
(-8625 3325);
DISPLAY 0.510638 (-8625 3325);
PAINT SKYBLUE (-8625 3325);
DISPLAY INVISIBLE (-8625 3325);
FORCEPROP 1 LAST MATERIAL CHIP
J 0
(-8650 3300);
DISPLAY 0.489362 (-8650 3300);
PAINT SKYBLUE (-8650 3300);
DISPLAY INVISIBLE (-8650 3300);
FORCEPROP 1 LAST WATTAGE 1/16W
J 2
(-8775 3175);
DISPLAY 0.510638 (-8775 3175);
PAINT SKYBLUE (-8775 3175);
DISPLAY INVISIBLE (-8775 3175);
FORCEPROP 2 LAST CDS_LIB pure_quanta
J 0
(-8750 3325);
DISPLAY INVISIBLE (-8750 3325);
FORCEPROP 1 LAST PATH I388
J 0
(-8800 3475);
DISPLAY 0.978723 (-8800 3475);
PAINT WHITE (-8800 3475);
DISPLAY INVISIBLE (-8800 3475);
FORCEPROP 1 LAST PART_NUMBER CS22202JB07
J 0
(-8800 3425);
DISPLAY 0.510638 (-8800 3425);
PAINT SKYBLUE (-8800 3425);
DISPLAY INVISIBLE (-8800 3425);
FORCEADD UNIVERSAL_POWER..1
(-9050 3600);
FORCEPROP 3 LASTPIN (-9050 3550) SIG_NAME P3V3_AUX\g
J 0
(-9040 3560);
DISPLAY 0.659574 (-9040 3560);
PAINT MONO (-9040 3560);
DISPLAY INVISIBLE (-9040 3560);
FORCEPROP 1 LAST HDL_POWER P3V3_AUX
J 1
(-9050 3650);
DISPLAY 0.489362 (-9050 3650);
PAINT GREEN (-9050 3650);
FORCEPROP 2 LAST CDS_LIB pure_quanta_power
J 0
(-9050 3600);
DISPLAY INVISIBLE (-9050 3600);
FORCEPROP 1 LAST PATH I389
J 0
(-9000 3625);
DISPLAY 0.872340 (-9000 3625);
PAINT AQUA (-9000 3625);
DISPLAY INVISIBLE (-9000 3625);
FORCEADD Q_RES..1
(-8750 3175);
FORCEPROP 1 LAST LOCATION R513
J 2
(-8925 3175);
DISPLAY 0.489362 (-8925 3175);
PAINT SKYBLUE (-8925 3175);
FORCEPROP 0 LAST $SEC 1
J 0
(-8625 3200);
DISPLAY 0.680851 (-8625 3200);
PAINT MONO (-8625 3200);
DISPLAY INVISIBLE (-8625 3200);
FORCEPROP 0 LAST CDS_SEC 1
J 0
(-8625 3200);
DISPLAY 0.680851 (-8625 3200);
DISPLAY INVISIBLE (-8625 3200);
FORCEPROP 1 LASTPIN (-8850 3175) $PN 1
J 0
(-8838 3187);
DISPLAY 0.489362 (-8838 3187);
PAINT MONO (-8838 3187);
FORCEPROP 1 LASTPIN (-8650 3175) $PN 2
J 0
(-8688 3187);
DISPLAY 0.489362 (-8688 3187);
PAINT MONO (-8688 3187);
FORCEPROP 1 LAST VALUE 2.2K
J 0
(-8625 3175);
DISPLAY 0.489362 (-8625 3175);
PAINT SKYBLUE (-8625 3175);
FORCEPROP 1 LAST PACK_TYPE 0402LF
J 0
(-8500 3025);
DISPLAY 0.510638 (-8500 3025);
PAINT SKYBLUE (-8500 3025);
DISPLAY INVISIBLE (-8500 3025);
FORCEPROP 1 LAST TOLERANCE 5%
J 0
(-8625 3175);
DISPLAY 0.510638 (-8625 3175);
PAINT SKYBLUE (-8625 3175);
DISPLAY INVISIBLE (-8625 3175);
FORCEPROP 1 LAST MATERIAL CHIP
J 0
(-8650 3150);
DISPLAY 0.489362 (-8650 3150);
PAINT SKYBLUE (-8650 3150);
DISPLAY INVISIBLE (-8650 3150);
FORCEPROP 1 LAST WATTAGE 1/16W
J 2
(-8775 3025);
DISPLAY 0.510638 (-8775 3025);
PAINT SKYBLUE (-8775 3025);
DISPLAY INVISIBLE (-8775 3025);
FORCEPROP 2 LAST CDS_LIB pure_quanta
J 0
(-8750 3175);
DISPLAY INVISIBLE (-8750 3175);
FORCEPROP 1 LAST PATH I390
J 0
(-8800 3325);
DISPLAY 0.978723 (-8800 3325);
PAINT WHITE (-8800 3325);
DISPLAY INVISIBLE (-8800 3325);
FORCEPROP 1 LAST PART_NUMBER CS22202JB07
J 0
(-8800 3275);
DISPLAY 0.510638 (-8800 3275);
PAINT SKYBLUE (-8800 3275);
DISPLAY INVISIBLE (-8800 3275);
FORCEADD Q_RES..1
(-8750 3225);
FORCEPROP 1 LAST LOCATION R515
J 2
(-8925 3225);
DISPLAY 0.489362 (-8925 3225);
PAINT SKYBLUE (-8925 3225);
FORCEPROP 0 LAST $SEC 1
J 0
(-8625 3250);
DISPLAY 0.680851 (-8625 3250);
PAINT MONO (-8625 3250);
DISPLAY INVISIBLE (-8625 3250);
FORCEPROP 0 LAST CDS_SEC 1
J 0
(-8625 3250);
DISPLAY 0.680851 (-8625 3250);
DISPLAY INVISIBLE (-8625 3250);
FORCEPROP 1 LASTPIN (-8850 3225) $PN 1
J 0
(-8838 3237);
DISPLAY 0.489362 (-8838 3237);
PAINT MONO (-8838 3237);
FORCEPROP 1 LASTPIN (-8650 3225) $PN 2
J 0
(-8688 3237);
DISPLAY 0.489362 (-8688 3237);
PAINT MONO (-8688 3237);
FORCEPROP 1 LAST VALUE 2.2K
J 0
(-8625 3225);
DISPLAY 0.489362 (-8625 3225);
PAINT SKYBLUE (-8625 3225);
FORCEPROP 1 LAST PACK_TYPE 0402LF
J 0
(-8500 3075);
DISPLAY 0.510638 (-8500 3075);
PAINT SKYBLUE (-8500 3075);
DISPLAY INVISIBLE (-8500 3075);
FORCEPROP 1 LAST TOLERANCE 5%
J 0
(-8625 3225);
DISPLAY 0.510638 (-8625 3225);
PAINT SKYBLUE (-8625 3225);
DISPLAY INVISIBLE (-8625 3225);
FORCEPROP 1 LAST MATERIAL CHIP
J 0
(-8650 3200);
DISPLAY 0.489362 (-8650 3200);
PAINT SKYBLUE (-8650 3200);
DISPLAY INVISIBLE (-8650 3200);
FORCEPROP 1 LAST WATTAGE 1/16W
J 2
(-8775 3075);
DISPLAY 0.510638 (-8775 3075);
PAINT SKYBLUE (-8775 3075);
DISPLAY INVISIBLE (-8775 3075);
FORCEPROP 2 LAST CDS_LIB pure_quanta
J 0
(-8750 3225);
DISPLAY INVISIBLE (-8750 3225);
FORCEPROP 1 LAST PATH I391
J 0
(-8800 3375);
DISPLAY 0.978723 (-8800 3375);
PAINT WHITE (-8800 3375);
DISPLAY INVISIBLE (-8800 3375);
FORCEPROP 1 LAST PART_NUMBER CS22202JB07
J 0
(-8800 3325);
DISPLAY 0.510638 (-8800 3325);
PAINT SKYBLUE (-8800 3325);
DISPLAY INVISIBLE (-8800 3325);
FORCEADD Q_RES..1
(-500 5575);
FORCEPROP 1 LAST LOCATION R520
J 0
(-750 5575);
DISPLAY 0.489362 (-750 5575);
PAINT SKYBLUE (-750 5575);
FORCEPROP 0 LAST $SEC 1
J 0
(-250 5600);
DISPLAY 0.680851 (-250 5600);
PAINT MONO (-250 5600);
DISPLAY INVISIBLE (-250 5600);
FORCEPROP 0 LAST CDS_SEC 1
J 0
(-250 5600);
DISPLAY 0.680851 (-250 5600);
DISPLAY INVISIBLE (-250 5600);
FORCEPROP 1 LASTPIN (-600 5575) $PN 1
J 0
(-588 5587);
DISPLAY 0.489362 (-588 5587);
PAINT MONO (-588 5587);
FORCEPROP 1 LASTPIN (-400 5575) $PN 2
J 0
(-438 5587);
DISPLAY 0.489362 (-438 5587);
PAINT MONO (-438 5587);
FORCEPROP 1 LAST VALUE 2.2K
J 2
(-250 5575);
DISPLAY 0.489362 (-250 5575);
PAINT SKYBLUE (-250 5575);
FORCEPROP 1 LAST WATTAGE 1/16W
J 2
(-525 5425);
DISPLAY 0.978723 (-525 5425);
PAINT SKYBLUE (-525 5425);
DISPLAY INVISIBLE (-525 5425);
FORCEPROP 1 LAST MATERIAL CHIP
J 0
(-500 5425);
DISPLAY 0.978723 (-500 5425);
PAINT SKYBLUE (-500 5425);
DISPLAY INVISIBLE (-500 5425);
FORCEPROP 1 LAST TOLERANCE 5%
J 0
(-500 5475);
DISPLAY 0.978723 (-500 5475);
PAINT SKYBLUE (-500 5475);
DISPLAY INVISIBLE (-500 5475);
FORCEPROP 1 LAST PACK_TYPE 0402LF
J 0
(-250 5425);
DISPLAY 0.978723 (-250 5425);
PAINT SKYBLUE (-250 5425);
DISPLAY INVISIBLE (-250 5425);
FORCEPROP 2 LAST CDS_LIB pure_quanta
J 0
(-500 5575);
DISPLAY INVISIBLE (-500 5575);
FORCEPROP 1 LAST PATH I396
J 0
(-550 5725);
DISPLAY 0.978723 (-550 5725);
PAINT WHITE (-550 5725);
DISPLAY INVISIBLE (-550 5725);
FORCEPROP 1 LAST PART_NUMBER CS22202JB07
J 0
(-550 5675);
DISPLAY 0.978723 (-550 5675);
PAINT SKYBLUE (-550 5675);
DISPLAY INVISIBLE (-550 5675);
FORCEADD OFFPAGE..2
R 2
(-1400 5575);
FORCEPROP 2 LAST $XR1 54 
J 0
(-1714 5575);
DISPLAY 0.638298 (-1714 5575);
PAINT MONO (-1714 5575);
FORCEPROP 2 LAST $XR0 82 
J 0
(-1624 5575);
DISPLAY 0.638298 (-1624 5575);
PAINT MONO (-1624 5575);
FORCEPROP 2 LAST CDS_LIB standard
J 0
(-1400 5575);
DISPLAY INVISIBLE (-1400 5575);
FORCEPROP 1 LAST OFFPAGE TRUE
J 2
(-1725 5450);
DISPLAY 0.872340 (-1725 5450);
PAINT GREEN (-1725 5450);
DISPLAY INVISIBLE (-1725 5450);
FORCEPROP 1 LAST COMMENT_BODY TRUE
J 2
(-1355 5480);
DISPLAY 0.872340 (-1355 5480);
PAINT PEACH (-1355 5480);
DISPLAY INVISIBLE (-1355 5480);
FORCEPROP 2 LAST PATH I397
J 0
(-1350 5650);
DISPLAY 0.680851 (-1350 5650);
DISPLAY INVISIBLE (-1350 5650);
FORCEADD Q_RES..1
(-500 5875);
FORCEPROP 1 LAST LOCATION R535
J 0
(-750 5875);
DISPLAY 0.489362 (-750 5875);
PAINT SKYBLUE (-750 5875);
FORCEPROP 0 LAST $SEC 1
J 0
(-250 5900);
DISPLAY 0.680851 (-250 5900);
PAINT MONO (-250 5900);
DISPLAY INVISIBLE (-250 5900);
FORCEPROP 0 LAST CDS_SEC 1
J 0
(-250 5900);
DISPLAY 0.680851 (-250 5900);
DISPLAY INVISIBLE (-250 5900);
FORCEPROP 1 LASTPIN (-600 5875) $PN 1
J 0
(-588 5887);
DISPLAY 0.489362 (-588 5887);
PAINT MONO (-588 5887);
FORCEPROP 1 LASTPIN (-400 5875) $PN 2
J 0
(-438 5887);
DISPLAY 0.489362 (-438 5887);
PAINT MONO (-438 5887);
FORCEPROP 1 LAST VALUE 2.2K
J 2
(-250 5875);
DISPLAY 0.489362 (-250 5875);
PAINT SKYBLUE (-250 5875);
FORCEPROP 2 LAST CDS_LIB pure_quanta
J 0
(-500 5875);
DISPLAY INVISIBLE (-500 5875);
FORCEPROP 1 LAST WATTAGE 1/16W
J 2
(-525 5725);
DISPLAY 0.978723 (-525 5725);
PAINT SKYBLUE (-525 5725);
DISPLAY INVISIBLE (-525 5725);
FORCEPROP 1 LAST MATERIAL CHIP
J 0
(-500 5725);
DISPLAY 0.978723 (-500 5725);
PAINT SKYBLUE (-500 5725);
DISPLAY INVISIBLE (-500 5725);
FORCEPROP 1 LAST TOLERANCE 5%
J 0
(-500 5775);
DISPLAY 0.978723 (-500 5775);
PAINT SKYBLUE (-500 5775);
DISPLAY INVISIBLE (-500 5775);
FORCEPROP 1 LAST PACK_TYPE 0402LF
J 0
(-250 5725);
DISPLAY 0.978723 (-250 5725);
PAINT SKYBLUE (-250 5725);
DISPLAY INVISIBLE (-250 5725);
FORCEPROP 1 LAST PATH I398
J 0
(-550 6025);
DISPLAY 0.978723 (-550 6025);
PAINT WHITE (-550 6025);
DISPLAY INVISIBLE (-550 6025);
FORCEPROP 1 LAST PART_NUMBER CS22202JB07
J 0
(-550 5975);
DISPLAY 0.978723 (-550 5975);
PAINT SKYBLUE (-550 5975);
DISPLAY INVISIBLE (-550 5975);
FORCEADD Q_RES..1
(-8750 3025);
FORCEPROP 1 LAST LOCATION R512
J 0
(-9000 3025);
DISPLAY 0.489362 (-9000 3025);
PAINT SKYBLUE (-9000 3025);
FORCEPROP 0 LAST $SEC 1
J 0
(-8625 3050);
DISPLAY 0.680851 (-8625 3050);
PAINT MONO (-8625 3050);
DISPLAY INVISIBLE (-8625 3050);
FORCEPROP 0 LAST CDS_SEC 1
J 0
(-8625 3050);
DISPLAY 0.680851 (-8625 3050);
DISPLAY INVISIBLE (-8625 3050);
FORCEPROP 1 LASTPIN (-8850 3025) $PN 1
J 0
(-8838 3037);
DISPLAY 0.489362 (-8838 3037);
PAINT MONO (-8838 3037);
FORCEPROP 1 LASTPIN (-8650 3025) $PN 2
J 0
(-8688 3037);
DISPLAY 0.489362 (-8688 3037);
PAINT MONO (-8688 3037);
FORCEPROP 1 LAST VALUE 2.2K
J 0
(-8625 3025);
DISPLAY 0.489362 (-8625 3025);
PAINT SKYBLUE (-8625 3025);
FORCEPROP 1 LAST PACK_TYPE 0402LF
J 0
(-8500 2875);
DISPLAY 0.978723 (-8500 2875);
PAINT SKYBLUE (-8500 2875);
DISPLAY INVISIBLE (-8500 2875);
FORCEPROP 1 LAST TOLERANCE 5%
J 0
(-8750 2925);
DISPLAY 0.978723 (-8750 2925);
PAINT SKYBLUE (-8750 2925);
DISPLAY INVISIBLE (-8750 2925);
FORCEPROP 1 LAST MATERIAL CHIP
J 0
(-8750 2875);
DISPLAY 0.978723 (-8750 2875);
PAINT SKYBLUE (-8750 2875);
DISPLAY INVISIBLE (-8750 2875);
FORCEPROP 1 LAST WATTAGE 1/16W
J 2
(-8775 2875);
DISPLAY 0.978723 (-8775 2875);
PAINT SKYBLUE (-8775 2875);
DISPLAY INVISIBLE (-8775 2875);
FORCEPROP 2 LAST CDS_LIB pure_quanta
J 0
(-8750 3025);
DISPLAY INVISIBLE (-8750 3025);
FORCEPROP 1 LAST PATH I400
J 0
(-8800 3175);
DISPLAY 0.978723 (-8800 3175);
PAINT WHITE (-8800 3175);
DISPLAY INVISIBLE (-8800 3175);
FORCEPROP 1 LAST PART_NUMBER CS22202JB07
J 0
(-8800 3125);
DISPLAY 0.978723 (-8800 3125);
PAINT SKYBLUE (-8800 3125);
DISPLAY INVISIBLE (-8800 3125);
FORCEADD Q_RES..1
(-8750 3075);
FORCEPROP 1 LAST LOCATION R514
J 0
(-9000 3075);
DISPLAY 0.489362 (-9000 3075);
PAINT SKYBLUE (-9000 3075);
FORCEPROP 0 LAST $SEC 1
J 0
(-8625 3100);
DISPLAY 0.680851 (-8625 3100);
PAINT MONO (-8625 3100);
DISPLAY INVISIBLE (-8625 3100);
FORCEPROP 0 LAST CDS_SEC 1
J 0
(-8625 3100);
DISPLAY 0.680851 (-8625 3100);
DISPLAY INVISIBLE (-8625 3100);
FORCEPROP 1 LASTPIN (-8850 3075) $PN 1
J 0
(-8838 3087);
DISPLAY 0.489362 (-8838 3087);
PAINT MONO (-8838 3087);
FORCEPROP 1 LASTPIN (-8650 3075) $PN 2
J 0
(-8688 3087);
DISPLAY 0.489362 (-8688 3087);
PAINT MONO (-8688 3087);
FORCEPROP 1 LAST VALUE 2.2K
J 0
(-8625 3075);
DISPLAY 0.489362 (-8625 3075);
PAINT SKYBLUE (-8625 3075);
FORCEPROP 1 LAST PACK_TYPE 0402LF
J 0
(-8500 2925);
DISPLAY 0.978723 (-8500 2925);
PAINT SKYBLUE (-8500 2925);
DISPLAY INVISIBLE (-8500 2925);
FORCEPROP 1 LAST TOLERANCE 5%
J 0
(-8750 2975);
DISPLAY 0.978723 (-8750 2975);
PAINT SKYBLUE (-8750 2975);
DISPLAY INVISIBLE (-8750 2975);
FORCEPROP 1 LAST MATERIAL CHIP
J 0
(-8750 2925);
DISPLAY 0.978723 (-8750 2925);
PAINT SKYBLUE (-8750 2925);
DISPLAY INVISIBLE (-8750 2925);
FORCEPROP 1 LAST WATTAGE 1/16W
J 2
(-8775 2925);
DISPLAY 0.978723 (-8775 2925);
PAINT SKYBLUE (-8775 2925);
DISPLAY INVISIBLE (-8775 2925);
FORCEPROP 2 LAST CDS_LIB pure_quanta
J 0
(-8750 3075);
DISPLAY INVISIBLE (-8750 3075);
FORCEPROP 1 LAST PATH I401
J 0
(-8800 3225);
DISPLAY 0.978723 (-8800 3225);
PAINT WHITE (-8800 3225);
DISPLAY INVISIBLE (-8800 3225);
FORCEPROP 1 LAST PART_NUMBER CS22202JB07
J 0
(-8800 3175);
DISPLAY 0.978723 (-8800 3175);
PAINT SKYBLUE (-8800 3175);
DISPLAY INVISIBLE (-8800 3175);
FORCEADD Q_RES..1
(-8750 3125);
FORCEPROP 1 LAST LOCATION R516
J 0
(-9000 3125);
DISPLAY 0.489362 (-9000 3125);
PAINT SKYBLUE (-9000 3125);
FORCEPROP 0 LAST $SEC 1
J 0
(-8625 3150);
DISPLAY 0.680851 (-8625 3150);
PAINT MONO (-8625 3150);
DISPLAY INVISIBLE (-8625 3150);
FORCEPROP 0 LAST CDS_SEC 1
J 0
(-8625 3150);
DISPLAY 0.680851 (-8625 3150);
DISPLAY INVISIBLE (-8625 3150);
FORCEPROP 1 LASTPIN (-8850 3125) $PN 1
J 0
(-8838 3137);
DISPLAY 0.489362 (-8838 3137);
PAINT MONO (-8838 3137);
FORCEPROP 1 LASTPIN (-8650 3125) $PN 2
J 0
(-8688 3137);
DISPLAY 0.489362 (-8688 3137);
PAINT MONO (-8688 3137);
FORCEPROP 1 LAST VALUE 2.2K
J 0
(-8625 3125);
DISPLAY 0.489362 (-8625 3125);
PAINT SKYBLUE (-8625 3125);
FORCEPROP 1 LAST PACK_TYPE 0402LF
J 0
(-8500 2975);
DISPLAY 0.978723 (-8500 2975);
PAINT SKYBLUE (-8500 2975);
DISPLAY INVISIBLE (-8500 2975);
FORCEPROP 1 LAST TOLERANCE 5%
J 0
(-8750 3025);
DISPLAY 0.978723 (-8750 3025);
PAINT SKYBLUE (-8750 3025);
DISPLAY INVISIBLE (-8750 3025);
FORCEPROP 1 LAST MATERIAL CHIP
J 0
(-8750 2975);
DISPLAY 0.978723 (-8750 2975);
PAINT SKYBLUE (-8750 2975);
DISPLAY INVISIBLE (-8750 2975);
FORCEPROP 1 LAST WATTAGE 1/16W
J 2
(-8775 2975);
DISPLAY 0.978723 (-8775 2975);
PAINT SKYBLUE (-8775 2975);
DISPLAY INVISIBLE (-8775 2975);
FORCEPROP 2 LAST CDS_LIB pure_quanta
J 0
(-8750 3125);
DISPLAY INVISIBLE (-8750 3125);
FORCEPROP 1 LAST PATH I402
J 0
(-8800 3275);
DISPLAY 0.978723 (-8800 3275);
PAINT WHITE (-8800 3275);
DISPLAY INVISIBLE (-8800 3275);
FORCEPROP 1 LAST PART_NUMBER CS22202JB07
J 0
(-8800 3225);
DISPLAY 0.978723 (-8800 3225);
PAINT SKYBLUE (-8800 3225);
DISPLAY INVISIBLE (-8800 3225);
FORCEADD Q_RES..2
R 2
(-8750 4825);
FORCEPROP 1 LAST LOCATION R518
J 2
(-8800 4900);
DISPLAY 0.489362 (-8800 4900);
PAINT SKYBLUE (-8800 4900);
FORCEPROP 0 LAST $SEC 1
J 0
(-8800 4925);
DISPLAY 0.680851 (-8800 4925);
PAINT MONO (-8800 4925);
DISPLAY INVISIBLE (-8800 4925);
FORCEPROP 0 LAST CDS_SEC 1
J 0
(-8800 4925);
DISPLAY 0.680851 (-8800 4925);
DISPLAY INVISIBLE (-8800 4925);
FORCEPROP 1 LASTPIN (-8750 4925) $PN 1
J 2
(-8755 4887);
DISPLAY 0.489362 (-8755 4887);
PAINT MONO (-8755 4887);
FORCEPROP 1 LASTPIN (-8750 4725) $PN 2
J 2
(-8755 4735);
DISPLAY 0.489362 (-8755 4735);
PAINT MONO (-8755 4735);
FORCEPROP 1 LAST PACK_TYPE 0402LF
J 2
(-8800 4750);
DISPLAY 0.489362 (-8800 4750);
PAINT SKYBLUE (-8800 4750);
FORCEPROP 1 LAST VALUE 2.2K
J 2
(-8800 4850);
DISPLAY 0.489362 (-8800 4850);
PAINT SKYBLUE (-8800 4850);
FORCEPROP 1 LAST MATERIAL CHIP
J 2
(-8800 4800);
DISPLAY 0.489362 (-8800 4800);
PAINT SKYBLUE (-8800 4800);
FORCEPROP 1 LAST TOLERANCE 5%
J 2
(-8795 4850);
DISPLAY 0.510638 (-8795 4850);
PAINT SKYBLUE (-8795 4850);
DISPLAY INVISIBLE (-8795 4850);
FORCEPROP 1 LAST WATTAGE 1/16W
J 2
(-8790 4800);
DISPLAY 0.510638 (-8790 4800);
PAINT SKYBLUE (-8790 4800);
DISPLAY INVISIBLE (-8790 4800);
FORCEPROP 2 LAST CDS_LIB pure_quanta
J 2
(-8750 4825);
DISPLAY INVISIBLE (-8750 4825);
FORCEPROP 1 LAST PATH I403
J 2
(-8800 5000);
DISPLAY 0.978723 (-8800 5000);
PAINT WHITE (-8800 5000);
DISPLAY INVISIBLE (-8800 5000);
FORCEPROP 1 LAST PART_NUMBER CS22202JB07
J 2
(-8790 4700);
DISPLAY 0.510638 (-8790 4700);
PAINT SKYBLUE (-8790 4700);
DISPLAY INVISIBLE (-8790 4700);
FORCEADD Q_RES..2
R 2
(-8750 4475);
FORCEPROP 1 LAST LOCATION R519
J 2
(-8800 4550);
DISPLAY 0.489362 (-8800 4550);
PAINT SKYBLUE (-8800 4550);
FORCEPROP 0 LAST $SEC 1
J 0
(-8800 4575);
DISPLAY 0.680851 (-8800 4575);
PAINT MONO (-8800 4575);
DISPLAY INVISIBLE (-8800 4575);
FORCEPROP 0 LAST CDS_SEC 1
J 0
(-8800 4575);
DISPLAY 0.680851 (-8800 4575);
DISPLAY INVISIBLE (-8800 4575);
FORCEPROP 1 LASTPIN (-8750 4575) $PN 1
J 2
(-8755 4537);
DISPLAY 0.489362 (-8755 4537);
PAINT MONO (-8755 4537);
FORCEPROP 1 LASTPIN (-8750 4375) $PN 2
J 2
(-8755 4385);
DISPLAY 0.489362 (-8755 4385);
PAINT MONO (-8755 4385);
FORCEPROP 1 LAST PACK_TYPE 0402LF
J 2
(-8800 4400);
DISPLAY 0.489362 (-8800 4400);
PAINT SKYBLUE (-8800 4400);
FORCEPROP 1 LAST VALUE 2.2K
J 2
(-8800 4500);
DISPLAY 0.489362 (-8800 4500);
PAINT SKYBLUE (-8800 4500);
FORCEPROP 1 LAST MATERIAL EMPTY
J 2
(-8800 4450);
DISPLAY 0.489362 (-8800 4450);
PAINT RED (-8800 4450);
FORCEPROP 1 LAST TOLERANCE 5%
J 2
(-8795 4500);
DISPLAY 0.510638 (-8795 4500);
PAINT SKYBLUE (-8795 4500);
DISPLAY INVISIBLE (-8795 4500);
FORCEPROP 1 LAST WATTAGE 1/16W
J 2
(-8790 4450);
DISPLAY 0.510638 (-8790 4450);
PAINT SKYBLUE (-8790 4450);
DISPLAY INVISIBLE (-8790 4450);
FORCEPROP 2 LAST CDS_LIB pure_quanta
J 0
(-8750 4475);
DISPLAY INVISIBLE (-8750 4475);
FORCEPROP 1 LAST PATH I404
J 2
(-8800 4650);
DISPLAY 0.978723 (-8800 4650);
PAINT WHITE (-8800 4650);
DISPLAY INVISIBLE (-8800 4650);
FORCEPROP 1 LAST PART_NUMBER CS22202JB07
J 2
(-8790 4350);
DISPLAY 0.510638 (-8790 4350);
PAINT SKYBLUE (-8790 4350);
DISPLAY INVISIBLE (-8790 4350);
FORCEADD Q_RES..2
(-8625 4475);
FORCEPROP 1 LAST LOCATION R521
J 0
(-8575 4550);
DISPLAY 0.489362 (-8575 4550);
PAINT SKYBLUE (-8575 4550);
FORCEPROP 0 LAST $SEC 1
J 0
(-8575 4575);
DISPLAY 0.680851 (-8575 4575);
PAINT MONO (-8575 4575);
DISPLAY INVISIBLE (-8575 4575);
FORCEPROP 0 LAST CDS_SEC 1
J 0
(-8575 4575);
DISPLAY 0.680851 (-8575 4575);
DISPLAY INVISIBLE (-8575 4575);
FORCEPROP 1 LASTPIN (-8625 4575) $PN 1
J 0
(-8620 4537);
DISPLAY 0.489362 (-8620 4537);
PAINT MONO (-8620 4537);
FORCEPROP 1 LASTPIN (-8625 4375) $PN 2
J 0
(-8620 4385);
DISPLAY 0.489362 (-8620 4385);
PAINT MONO (-8620 4385);
FORCEPROP 1 LAST PACK_TYPE 0402LF
J 0
(-8575 4400);
DISPLAY 0.489362 (-8575 4400);
PAINT SKYBLUE (-8575 4400);
FORCEPROP 1 LAST VALUE 2.2K
J 0
(-8575 4500);
DISPLAY 0.489362 (-8575 4500);
PAINT SKYBLUE (-8575 4500);
FORCEPROP 1 LAST MATERIAL CHIP
J 0
(-8575 4450);
DISPLAY 0.489362 (-8575 4450);
PAINT SKYBLUE (-8575 4450);
FORCEPROP 1 LAST TOLERANCE 5%
J 0
(-8580 4500);
DISPLAY 0.510638 (-8580 4500);
PAINT SKYBLUE (-8580 4500);
DISPLAY INVISIBLE (-8580 4500);
FORCEPROP 1 LAST WATTAGE 1/16W
J 0
(-8585 4450);
DISPLAY 0.510638 (-8585 4450);
PAINT SKYBLUE (-8585 4450);
DISPLAY INVISIBLE (-8585 4450);
FORCEPROP 2 LAST CDS_LIB pure_quanta
J 2
(-8625 4475);
DISPLAY INVISIBLE (-8625 4475);
FORCEPROP 1 LAST PATH I405
J 0
(-8575 4650);
DISPLAY 0.978723 (-8575 4650);
PAINT WHITE (-8575 4650);
DISPLAY INVISIBLE (-8575 4650);
FORCEPROP 1 LAST PART_NUMBER CS22202JB07
J 0
(-8585 4350);
DISPLAY 0.510638 (-8585 4350);
PAINT SKYBLUE (-8585 4350);
DISPLAY INVISIBLE (-8585 4350);
FORCEADD Q_RES..1
(-500 6075);
FORCEPROP 1 LAST LOCATION R531
J 0
(-750 6075);
DISPLAY 0.489362 (-750 6075);
PAINT SKYBLUE (-750 6075);
FORCEPROP 0 LAST $SEC 1
J 0
(-250 6100);
DISPLAY 0.680851 (-250 6100);
PAINT MONO (-250 6100);
DISPLAY INVISIBLE (-250 6100);
FORCEPROP 0 LAST CDS_SEC 1
J 0
(-250 6100);
DISPLAY 0.680851 (-250 6100);
DISPLAY INVISIBLE (-250 6100);
FORCEPROP 1 LASTPIN (-600 6075) $PN 1
J 0
(-588 6087);
DISPLAY 0.489362 (-588 6087);
PAINT MONO (-588 6087);
FORCEPROP 1 LASTPIN (-400 6075) $PN 2
J 0
(-438 6087);
DISPLAY 0.489362 (-438 6087);
PAINT MONO (-438 6087);
FORCEPROP 1 LAST VALUE 2.2K
J 2
(-250 6075);
DISPLAY 0.489362 (-250 6075);
PAINT SKYBLUE (-250 6075);
FORCEPROP 1 LAST PACK_TYPE 0402LF
J 0
(-250 5925);
DISPLAY 0.978723 (-250 5925);
PAINT SKYBLUE (-250 5925);
DISPLAY INVISIBLE (-250 5925);
FORCEPROP 1 LAST TOLERANCE 5%
J 0
(-500 5975);
DISPLAY 0.978723 (-500 5975);
PAINT SKYBLUE (-500 5975);
DISPLAY INVISIBLE (-500 5975);
FORCEPROP 1 LAST MATERIAL CHIP
J 0
(-500 5925);
DISPLAY 0.978723 (-500 5925);
PAINT SKYBLUE (-500 5925);
DISPLAY INVISIBLE (-500 5925);
FORCEPROP 1 LAST WATTAGE 1/16W
J 2
(-525 5925);
DISPLAY 0.978723 (-525 5925);
PAINT SKYBLUE (-525 5925);
DISPLAY INVISIBLE (-525 5925);
FORCEPROP 2 LAST CDS_LIB pure_quanta
J 0
(-500 6075);
DISPLAY INVISIBLE (-500 6075);
FORCEPROP 1 LAST PATH I406
J 0
(-550 6225);
DISPLAY 0.978723 (-550 6225);
PAINT WHITE (-550 6225);
DISPLAY INVISIBLE (-550 6225);
FORCEPROP 1 LAST PART_NUMBER CS22202JB07
J 0
(-550 6175);
DISPLAY 0.978723 (-550 6175);
PAINT SKYBLUE (-550 6175);
DISPLAY INVISIBLE (-550 6175);
FORCEADD Q_RES..1
(-500 6025);
FORCEPROP 1 LAST LOCATION R532
J 0
(-750 6025);
DISPLAY 0.489362 (-750 6025);
PAINT SKYBLUE (-750 6025);
FORCEPROP 0 LAST $SEC 1
J 0
(-250 6050);
DISPLAY 0.680851 (-250 6050);
PAINT MONO (-250 6050);
DISPLAY INVISIBLE (-250 6050);
FORCEPROP 0 LAST CDS_SEC 1
J 0
(-250 6050);
DISPLAY 0.680851 (-250 6050);
DISPLAY INVISIBLE (-250 6050);
FORCEPROP 1 LASTPIN (-600 6025) $PN 1
J 0
(-588 6037);
DISPLAY 0.489362 (-588 6037);
PAINT MONO (-588 6037);
FORCEPROP 1 LASTPIN (-400 6025) $PN 2
J 0
(-438 6037);
DISPLAY 0.489362 (-438 6037);
PAINT MONO (-438 6037);
FORCEPROP 1 LAST VALUE 2.2K
J 2
(-250 6025);
DISPLAY 0.489362 (-250 6025);
PAINT SKYBLUE (-250 6025);
FORCEPROP 1 LAST PACK_TYPE 0402LF
J 0
(-250 5875);
DISPLAY 0.978723 (-250 5875);
PAINT SKYBLUE (-250 5875);
DISPLAY INVISIBLE (-250 5875);
FORCEPROP 1 LAST TOLERANCE 5%
J 0
(-500 5925);
DISPLAY 0.978723 (-500 5925);
PAINT SKYBLUE (-500 5925);
DISPLAY INVISIBLE (-500 5925);
FORCEPROP 1 LAST MATERIAL CHIP
J 0
(-500 5875);
DISPLAY 0.978723 (-500 5875);
PAINT SKYBLUE (-500 5875);
DISPLAY INVISIBLE (-500 5875);
FORCEPROP 1 LAST WATTAGE 1/16W
J 2
(-525 5875);
DISPLAY 0.978723 (-525 5875);
PAINT SKYBLUE (-525 5875);
DISPLAY INVISIBLE (-525 5875);
FORCEPROP 2 LAST CDS_LIB pure_quanta
J 0
(-500 6025);
DISPLAY INVISIBLE (-500 6025);
FORCEPROP 1 LAST PATH I407
J 0
(-550 6175);
DISPLAY 0.978723 (-550 6175);
PAINT WHITE (-550 6175);
DISPLAY INVISIBLE (-550 6175);
FORCEPROP 1 LAST PART_NUMBER CS22202JB07
J 0
(-550 6125);
DISPLAY 0.978723 (-550 6125);
PAINT SKYBLUE (-550 6125);
DISPLAY INVISIBLE (-550 6125);
FORCEADD Q_RES..1
(-500 5975);
FORCEPROP 1 LAST LOCATION R533
J 0
(-750 5975);
DISPLAY 0.489362 (-750 5975);
PAINT SKYBLUE (-750 5975);
FORCEPROP 0 LAST $SEC 1
J 0
(-250 6000);
DISPLAY 0.680851 (-250 6000);
PAINT MONO (-250 6000);
DISPLAY INVISIBLE (-250 6000);
FORCEPROP 0 LAST CDS_SEC 1
J 0
(-250 6000);
DISPLAY 0.680851 (-250 6000);
DISPLAY INVISIBLE (-250 6000);
FORCEPROP 1 LASTPIN (-600 5975) $PN 1
J 0
(-588 5987);
DISPLAY 0.489362 (-588 5987);
PAINT MONO (-588 5987);
FORCEPROP 1 LASTPIN (-400 5975) $PN 2
J 0
(-438 5987);
DISPLAY 0.489362 (-438 5987);
PAINT MONO (-438 5987);
FORCEPROP 1 LAST VALUE 2.2K
J 2
(-250 5975);
DISPLAY 0.489362 (-250 5975);
PAINT SKYBLUE (-250 5975);
FORCEPROP 1 LAST PACK_TYPE 0402LF
J 0
(-250 5825);
DISPLAY 0.978723 (-250 5825);
PAINT SKYBLUE (-250 5825);
DISPLAY INVISIBLE (-250 5825);
FORCEPROP 1 LAST TOLERANCE 5%
J 0
(-500 5875);
DISPLAY 0.978723 (-500 5875);
PAINT SKYBLUE (-500 5875);
DISPLAY INVISIBLE (-500 5875);
FORCEPROP 1 LAST MATERIAL CHIP
J 0
(-500 5825);
DISPLAY 0.978723 (-500 5825);
PAINT SKYBLUE (-500 5825);
DISPLAY INVISIBLE (-500 5825);
FORCEPROP 1 LAST WATTAGE 1/16W
J 2
(-525 5825);
DISPLAY 0.978723 (-525 5825);
PAINT SKYBLUE (-525 5825);
DISPLAY INVISIBLE (-525 5825);
FORCEPROP 2 LAST CDS_LIB pure_quanta
J 0
(-500 5975);
DISPLAY INVISIBLE (-500 5975);
FORCEPROP 1 LAST PATH I408
J 0
(-550 6125);
DISPLAY 0.978723 (-550 6125);
PAINT WHITE (-550 6125);
DISPLAY INVISIBLE (-550 6125);
FORCEPROP 1 LAST PART_NUMBER CS22202JB07
J 0
(-550 6075);
DISPLAY 0.978723 (-550 6075);
PAINT SKYBLUE (-550 6075);
DISPLAY INVISIBLE (-550 6075);
FORCEADD Q_RES..1
(-500 5925);
FORCEPROP 1 LAST LOCATION R534
J 0
(-750 5925);
DISPLAY 0.489362 (-750 5925);
PAINT SKYBLUE (-750 5925);
FORCEPROP 0 LAST $SEC 1
J 0
(-250 5950);
DISPLAY 0.680851 (-250 5950);
PAINT MONO (-250 5950);
DISPLAY INVISIBLE (-250 5950);
FORCEPROP 0 LAST CDS_SEC 1
J 0
(-250 5950);
DISPLAY 0.680851 (-250 5950);
DISPLAY INVISIBLE (-250 5950);
FORCEPROP 1 LASTPIN (-600 5925) $PN 1
J 0
(-588 5937);
DISPLAY 0.489362 (-588 5937);
PAINT MONO (-588 5937);
FORCEPROP 1 LASTPIN (-400 5925) $PN 2
J 0
(-438 5937);
DISPLAY 0.489362 (-438 5937);
PAINT MONO (-438 5937);
FORCEPROP 1 LAST VALUE 2.2K
J 2
(-250 5925);
DISPLAY 0.489362 (-250 5925);
PAINT SKYBLUE (-250 5925);
FORCEPROP 1 LAST PACK_TYPE 0402LF
J 0
(-250 5775);
DISPLAY 0.978723 (-250 5775);
PAINT SKYBLUE (-250 5775);
DISPLAY INVISIBLE (-250 5775);
FORCEPROP 1 LAST TOLERANCE 5%
J 0
(-500 5825);
DISPLAY 0.978723 (-500 5825);
PAINT SKYBLUE (-500 5825);
DISPLAY INVISIBLE (-500 5825);
FORCEPROP 1 LAST MATERIAL CHIP
J 0
(-500 5775);
DISPLAY 0.978723 (-500 5775);
PAINT SKYBLUE (-500 5775);
DISPLAY INVISIBLE (-500 5775);
FORCEPROP 1 LAST WATTAGE 1/16W
J 2
(-525 5775);
DISPLAY 0.978723 (-525 5775);
PAINT SKYBLUE (-525 5775);
DISPLAY INVISIBLE (-525 5775);
FORCEPROP 2 LAST CDS_LIB pure_quanta
J 0
(-500 5925);
DISPLAY INVISIBLE (-500 5925);
FORCEPROP 1 LAST PATH I409
J 0
(-550 6075);
DISPLAY 0.978723 (-550 6075);
PAINT WHITE (-550 6075);
DISPLAY INVISIBLE (-550 6075);
FORCEPROP 1 LAST PART_NUMBER CS22202JB07
J 0
(-550 6025);
DISPLAY 0.978723 (-550 6025);
PAINT SKYBLUE (-550 6025);
DISPLAY INVISIBLE (-550 6025);
FORCEADD Q_RES..1
(-500 5775);
FORCEPROP 1 LAST LOCATION R537
J 0
(-750 5775);
DISPLAY 0.489362 (-750 5775);
PAINT SKYBLUE (-750 5775);
FORCEPROP 0 LAST $SEC 1
J 0
(-250 5800);
DISPLAY 0.680851 (-250 5800);
PAINT MONO (-250 5800);
DISPLAY INVISIBLE (-250 5800);
FORCEPROP 0 LAST CDS_SEC 1
J 0
(-250 5800);
DISPLAY 0.680851 (-250 5800);
DISPLAY INVISIBLE (-250 5800);
FORCEPROP 1 LASTPIN (-600 5775) $PN 1
J 0
(-588 5787);
DISPLAY 0.489362 (-588 5787);
PAINT MONO (-588 5787);
FORCEPROP 1 LASTPIN (-400 5775) $PN 2
J 0
(-438 5787);
DISPLAY 0.489362 (-438 5787);
PAINT MONO (-438 5787);
FORCEPROP 1 LAST VALUE 2.2K
J 2
(-250 5775);
DISPLAY 0.489362 (-250 5775);
PAINT SKYBLUE (-250 5775);
FORCEPROP 1 LAST PACK_TYPE 0402LF
J 0
(-250 5625);
DISPLAY 0.978723 (-250 5625);
PAINT SKYBLUE (-250 5625);
DISPLAY INVISIBLE (-250 5625);
FORCEPROP 1 LAST TOLERANCE 5%
J 0
(-500 5675);
DISPLAY 0.978723 (-500 5675);
PAINT SKYBLUE (-500 5675);
DISPLAY INVISIBLE (-500 5675);
FORCEPROP 1 LAST MATERIAL CHIP
J 0
(-500 5625);
DISPLAY 0.978723 (-500 5625);
PAINT SKYBLUE (-500 5625);
DISPLAY INVISIBLE (-500 5625);
FORCEPROP 1 LAST WATTAGE 1/16W
J 2
(-525 5625);
DISPLAY 0.978723 (-525 5625);
PAINT SKYBLUE (-525 5625);
DISPLAY INVISIBLE (-525 5625);
FORCEPROP 2 LAST CDS_LIB pure_quanta
J 0
(-500 5775);
DISPLAY INVISIBLE (-500 5775);
FORCEPROP 1 LAST PATH I410
J 0
(-550 5925);
DISPLAY 0.978723 (-550 5925);
PAINT WHITE (-550 5925);
DISPLAY INVISIBLE (-550 5925);
FORCEPROP 1 LAST PART_NUMBER CS22202JB07
J 0
(-550 5875);
DISPLAY 0.978723 (-550 5875);
PAINT SKYBLUE (-550 5875);
DISPLAY INVISIBLE (-550 5875);
FORCEADD Q_RES..1
(-500 5725);
FORCEPROP 1 LAST LOCATION R538
J 0
(-750 5725);
DISPLAY 0.489362 (-750 5725);
PAINT SKYBLUE (-750 5725);
FORCEPROP 0 LAST $SEC 1
J 0
(-250 5750);
DISPLAY 0.680851 (-250 5750);
PAINT MONO (-250 5750);
DISPLAY INVISIBLE (-250 5750);
FORCEPROP 0 LAST CDS_SEC 1
J 0
(-250 5750);
DISPLAY 0.680851 (-250 5750);
DISPLAY INVISIBLE (-250 5750);
FORCEPROP 1 LASTPIN (-600 5725) $PN 1
J 0
(-588 5737);
DISPLAY 0.489362 (-588 5737);
PAINT MONO (-588 5737);
FORCEPROP 1 LASTPIN (-400 5725) $PN 2
J 0
(-438 5737);
DISPLAY 0.489362 (-438 5737);
PAINT MONO (-438 5737);
FORCEPROP 1 LAST VALUE 2.2K
J 2
(-250 5725);
DISPLAY 0.489362 (-250 5725);
PAINT SKYBLUE (-250 5725);
FORCEPROP 1 LAST PACK_TYPE 0402LF
J 0
(-250 5575);
DISPLAY 0.978723 (-250 5575);
PAINT SKYBLUE (-250 5575);
DISPLAY INVISIBLE (-250 5575);
FORCEPROP 1 LAST TOLERANCE 5%
J 0
(-500 5625);
DISPLAY 0.978723 (-500 5625);
PAINT SKYBLUE (-500 5625);
DISPLAY INVISIBLE (-500 5625);
FORCEPROP 1 LAST MATERIAL CHIP
J 0
(-500 5575);
DISPLAY 0.978723 (-500 5575);
PAINT SKYBLUE (-500 5575);
DISPLAY INVISIBLE (-500 5575);
FORCEPROP 1 LAST WATTAGE 1/16W
J 2
(-525 5575);
DISPLAY 0.978723 (-525 5575);
PAINT SKYBLUE (-525 5575);
DISPLAY INVISIBLE (-525 5575);
FORCEPROP 2 LAST CDS_LIB pure_quanta
J 0
(-500 5725);
DISPLAY INVISIBLE (-500 5725);
FORCEPROP 1 LAST PATH I411
J 0
(-550 5875);
DISPLAY 0.978723 (-550 5875);
PAINT WHITE (-550 5875);
DISPLAY INVISIBLE (-550 5875);
FORCEPROP 1 LAST PART_NUMBER CS22202JB07
J 0
(-550 5825);
DISPLAY 0.978723 (-550 5825);
PAINT SKYBLUE (-550 5825);
DISPLAY INVISIBLE (-550 5825);
FORCEADD Q_RES..1
(-500 5675);
FORCEPROP 1 LAST LOCATION R539
J 0
(-750 5675);
DISPLAY 0.489362 (-750 5675);
PAINT SKYBLUE (-750 5675);
FORCEPROP 0 LAST $SEC 1
J 0
(-250 5700);
DISPLAY 0.680851 (-250 5700);
PAINT MONO (-250 5700);
DISPLAY INVISIBLE (-250 5700);
FORCEPROP 0 LAST CDS_SEC 1
J 0
(-250 5700);
DISPLAY 0.680851 (-250 5700);
DISPLAY INVISIBLE (-250 5700);
FORCEPROP 1 LASTPIN (-600 5675) $PN 1
J 0
(-588 5687);
DISPLAY 0.489362 (-588 5687);
PAINT MONO (-588 5687);
FORCEPROP 1 LASTPIN (-400 5675) $PN 2
J 0
(-438 5687);
DISPLAY 0.489362 (-438 5687);
PAINT MONO (-438 5687);
FORCEPROP 1 LAST VALUE 2.2K
J 2
(-250 5675);
DISPLAY 0.489362 (-250 5675);
PAINT SKYBLUE (-250 5675);
FORCEPROP 1 LAST PACK_TYPE 0402LF
J 0
(-250 5525);
DISPLAY 0.978723 (-250 5525);
PAINT SKYBLUE (-250 5525);
DISPLAY INVISIBLE (-250 5525);
FORCEPROP 1 LAST TOLERANCE 5%
J 0
(-500 5575);
DISPLAY 0.978723 (-500 5575);
PAINT SKYBLUE (-500 5575);
DISPLAY INVISIBLE (-500 5575);
FORCEPROP 1 LAST MATERIAL CHIP
J 0
(-500 5525);
DISPLAY 0.978723 (-500 5525);
PAINT SKYBLUE (-500 5525);
DISPLAY INVISIBLE (-500 5525);
FORCEPROP 1 LAST WATTAGE 1/16W
J 2
(-525 5525);
DISPLAY 0.978723 (-525 5525);
PAINT SKYBLUE (-525 5525);
DISPLAY INVISIBLE (-525 5525);
FORCEPROP 2 LAST CDS_LIB pure_quanta
J 0
(-500 5675);
DISPLAY INVISIBLE (-500 5675);
FORCEPROP 1 LAST PATH I412
J 0
(-550 5825);
DISPLAY 0.978723 (-550 5825);
PAINT WHITE (-550 5825);
DISPLAY INVISIBLE (-550 5825);
FORCEPROP 1 LAST PART_NUMBER CS22202JB07
J 0
(-550 5775);
DISPLAY 0.978723 (-550 5775);
PAINT SKYBLUE (-550 5775);
DISPLAY INVISIBLE (-550 5775);
FORCEADD Q_RES..1
(-500 5625);
FORCEPROP 1 LAST LOCATION R540
J 0
(-750 5625);
DISPLAY 0.489362 (-750 5625);
PAINT SKYBLUE (-750 5625);
FORCEPROP 0 LAST $SEC 1
J 0
(-250 5650);
DISPLAY 0.680851 (-250 5650);
PAINT MONO (-250 5650);
DISPLAY INVISIBLE (-250 5650);
FORCEPROP 0 LAST CDS_SEC 1
J 0
(-250 5650);
DISPLAY 0.680851 (-250 5650);
DISPLAY INVISIBLE (-250 5650);
FORCEPROP 1 LASTPIN (-600 5625) $PN 1
J 0
(-588 5637);
DISPLAY 0.489362 (-588 5637);
PAINT MONO (-588 5637);
FORCEPROP 1 LASTPIN (-400 5625) $PN 2
J 0
(-438 5637);
DISPLAY 0.489362 (-438 5637);
PAINT MONO (-438 5637);
FORCEPROP 1 LAST VALUE 2.2K
J 2
(-250 5625);
DISPLAY 0.489362 (-250 5625);
PAINT SKYBLUE (-250 5625);
FORCEPROP 1 LAST PACK_TYPE 0402LF
J 0
(-250 5475);
DISPLAY 0.978723 (-250 5475);
PAINT SKYBLUE (-250 5475);
DISPLAY INVISIBLE (-250 5475);
FORCEPROP 1 LAST TOLERANCE 5%
J 0
(-500 5525);
DISPLAY 0.978723 (-500 5525);
PAINT SKYBLUE (-500 5525);
DISPLAY INVISIBLE (-500 5525);
FORCEPROP 1 LAST MATERIAL CHIP
J 0
(-500 5475);
DISPLAY 0.978723 (-500 5475);
PAINT SKYBLUE (-500 5475);
DISPLAY INVISIBLE (-500 5475);
FORCEPROP 1 LAST WATTAGE 1/16W
J 2
(-525 5475);
DISPLAY 0.978723 (-525 5475);
PAINT SKYBLUE (-525 5475);
DISPLAY INVISIBLE (-525 5475);
FORCEPROP 2 LAST CDS_LIB pure_quanta
J 0
(-500 5625);
DISPLAY INVISIBLE (-500 5625);
FORCEPROP 1 LAST PATH I413
J 0
(-550 5775);
DISPLAY 0.978723 (-550 5775);
PAINT WHITE (-550 5775);
DISPLAY INVISIBLE (-550 5775);
FORCEPROP 1 LAST PART_NUMBER CS22202JB07
J 0
(-550 5725);
DISPLAY 0.978723 (-550 5725);
PAINT SKYBLUE (-550 5725);
DISPLAY INVISIBLE (-550 5725);
FORCEADD OFFPAGE..2
(-2375 4975);
FORCEPROP 2 LAST $XR1 82 
J 0
(-2096 4975);
DISPLAY 0.638298 (-2096 4975);
PAINT MONO (-2096 4975);
FORCEPROP 2 LAST $XR0 27 
J 0
(-2186 4975);
DISPLAY 0.638298 (-2186 4975);
PAINT MONO (-2186 4975);
FORCEPROP 2 LAST CDS_LIB standard
J 2
(-2375 4975);
DISPLAY INVISIBLE (-2375 4975);
FORCEPROP 1 LAST OFFPAGE TRUE
J 0
(-2050 4850);
DISPLAY 0.872340 (-2050 4850);
PAINT GREEN (-2050 4850);
DISPLAY INVISIBLE (-2050 4850);
FORCEPROP 1 LAST COMMENT_BODY TRUE
J 0
(-2420 4880);
DISPLAY 0.872340 (-2420 4880);
PAINT GREEN (-2420 4880);
DISPLAY INVISIBLE (-2420 4880);
FORCEPROP 2 LAST PATH I414
J 0
(-2075 5025);
DISPLAY 0.680851 (-2075 5025);
DISPLAY INVISIBLE (-2075 5025);
FORCEADD Q_RES..1
(-3100 4975);
FORCEPROP 1 LAST LOCATION R488
J 0
(-2975 4975);
DISPLAY 0.489362 (-2975 4975);
PAINT SKYBLUE (-2975 4975);
FORCEPROP 2 LAST $SEC 1
J 0
(-3150 5175);
DISPLAY 0.680851 (-3150 5175);
PAINT MONO (-3150 5175);
DISPLAY INVISIBLE (-3150 5175);
FORCEPROP 2 LAST CDS_SEC 1
J 0
(-3150 5175);
DISPLAY 0.680851 (-3150 5175);
DISPLAY INVISIBLE (-3150 5175);
FORCEPROP 1 LASTPIN (-3200 4975) $PN 1
J 0
(-3188 4987);
DISPLAY 0.489362 (-3188 4987);
PAINT MONO (-3188 4987);
FORCEPROP 1 LASTPIN (-3000 4975) $PN 2
J 0
(-3038 4987);
DISPLAY 0.489362 (-3038 4987);
PAINT MONO (-3038 4987);
FORCEPROP 1 LAST VALUE 33
J 2
(-3225 4975);
DISPLAY 0.489362 (-3225 4975);
PAINT SKYBLUE (-3225 4975);
FORCEPROP 1 LAST PACK_TYPE 0402LF
J 2
(-2925 4900);
DISPLAY 0.489362 (-2925 4900);
PAINT SKYBLUE (-2925 4900);
DISPLAY INVISIBLE (-2925 4900);
FORCEPROP 1 LAST TOLERANCE 5%
J 0
(-3225 4950);
DISPLAY 0.489362 (-3225 4950);
PAINT SKYBLUE (-3225 4950);
DISPLAY INVISIBLE (-3225 4950);
FORCEPROP 1 LAST MATERIAL CHIP
J 2
(-2925 4950);
DISPLAY 0.489362 (-2925 4950);
PAINT SKYBLUE (-2925 4950);
DISPLAY INVISIBLE (-2925 4950);
FORCEPROP 1 LAST WATTAGE 1/16W
J 2
(-3175 4900);
DISPLAY 0.489362 (-3175 4900);
PAINT SKYBLUE (-3175 4900);
DISPLAY INVISIBLE (-3175 4900);
FORCEPROP 2 LAST CDS_LIB pure_quanta
J 0
(-3100 4975);
DISPLAY INVISIBLE (-3100 4975);
FORCEPROP 2 LAST BOM_COST MEM
J 2
(-3075 5125);
DISPLAY 0.744681 (-3075 5125);
PAINT WHITE (-3075 5125);
DISPLAY INVISIBLE (-3075 5125);
FORCEPROP 1 LAST PATH I415
J 0
(-3150 5125);
DISPLAY 0.978723 (-3150 5125);
PAINT WHITE (-3150 5125);
DISPLAY INVISIBLE (-3150 5125);
FORCEPROP 1 LAST PART_NUMBER CS03302JB10
J 2
(-3000 5025);
DISPLAY 0.489362 (-3000 5025);
PAINT SKYBLUE (-3000 5025);
DISPLAY INVISIBLE (-3000 5025);
FORCEADD OFFPAGE..2
(-2350 5125);
FORCEPROP 2 LAST $XR0 81 
J 0
(-2161 5125);
DISPLAY 0.638298 (-2161 5125);
PAINT MONO (-2161 5125);
FORCEPROP 2 LAST CDS_LIB standard
J 2
(-2350 5125);
DISPLAY INVISIBLE (-2350 5125);
FORCEPROP 1 LAST OFFPAGE TRUE
J 0
(-2025 5000);
DISPLAY 0.872340 (-2025 5000);
PAINT GREEN (-2025 5000);
DISPLAY INVISIBLE (-2025 5000);
FORCEPROP 1 LAST COMMENT_BODY TRUE
J 0
(-2395 5030);
DISPLAY 0.872340 (-2395 5030);
PAINT GREEN (-2395 5030);
DISPLAY INVISIBLE (-2395 5030);
FORCEPROP 2 LAST PATH I416
J 0
(-2050 5175);
DISPLAY 0.680851 (-2050 5175);
DISPLAY INVISIBLE (-2050 5175);
FORCEADD Q_RES..1
(-3100 5125);
FORCEPROP 1 LAST LOCATION R497
J 0
(-2975 5125);
DISPLAY 0.489362 (-2975 5125);
PAINT SKYBLUE (-2975 5125);
FORCEPROP 0 LAST $SEC 1
J 0
(-2975 5175);
DISPLAY 0.680851 (-2975 5175);
PAINT MONO (-2975 5175);
DISPLAY INVISIBLE (-2975 5175);
FORCEPROP 0 LAST CDS_SEC 1
J 0
(-2975 5175);
DISPLAY 1.021277 (-2975 5175);
DISPLAY INVISIBLE (-2975 5175);
FORCEPROP 1 LASTPIN (-3200 5125) $PN 1
J 0
(-3188 5137);
DISPLAY 0.489362 (-3188 5137);
PAINT MONO (-3188 5137);
FORCEPROP 1 LASTPIN (-3000 5125) $PN 2
J 0
(-3038 5137);
DISPLAY 0.489362 (-3038 5137);
PAINT MONO (-3038 5137);
FORCEPROP 1 LAST VALUE 33
J 2
(-3225 5125);
DISPLAY 0.489362 (-3225 5125);
PAINT SKYBLUE (-3225 5125);
FORCEPROP 1 LAST PACK_TYPE 0402LF
J 2
(-2925 5050);
DISPLAY 0.489362 (-2925 5050);
PAINT SKYBLUE (-2925 5050);
DISPLAY INVISIBLE (-2925 5050);
FORCEPROP 1 LAST TOLERANCE 5%
J 0
(-3225 5100);
DISPLAY 0.489362 (-3225 5100);
PAINT SKYBLUE (-3225 5100);
DISPLAY INVISIBLE (-3225 5100);
FORCEPROP 1 LAST MATERIAL CHIP
J 2
(-2925 5100);
DISPLAY 0.489362 (-2925 5100);
PAINT SKYBLUE (-2925 5100);
DISPLAY INVISIBLE (-2925 5100);
FORCEPROP 1 LAST WATTAGE 1/16W
J 2
(-3175 5050);
DISPLAY 0.489362 (-3175 5050);
PAINT SKYBLUE (-3175 5050);
DISPLAY INVISIBLE (-3175 5050);
FORCEPROP 2 LAST CDS_LIB pure_quanta
J 0
(-3100 5125);
DISPLAY INVISIBLE (-3100 5125);
FORCEPROP 2 LAST BOM_COST MEM
J 2
(-3075 5275);
DISPLAY 0.744681 (-3075 5275);
PAINT WHITE (-3075 5275);
DISPLAY INVISIBLE (-3075 5275);
FORCEPROP 1 LAST PATH I417
J 0
(-3150 5275);
DISPLAY 0.978723 (-3150 5275);
PAINT WHITE (-3150 5275);
DISPLAY INVISIBLE (-3150 5275);
FORCEPROP 1 LAST PART_NUMBER CS03302JB10
J 2
(-3000 5175);
DISPLAY 0.489362 (-3000 5175);
PAINT SKYBLUE (-3000 5175);
DISPLAY INVISIBLE (-3000 5175);
FORCEADD SCONN8_G802M0083150RD3HR..1
(-500 3575);
FORCEPROP 1 LAST LOCATION J7
J 0
(-769 3806);
DISPLAY 0.723404 (-769 3806);
PAINT GREEN (-769 3806);
FORCEPROP 2 LAST SEC 1
J 0
(-625 3950);
DISPLAY 0.680851 (-625 3950);
PAINT MONO (-625 3950);
DISPLAY INVISIBLE (-625 3950);
FORCEPROP 2 LASTPIN (-775 3650) $PN 1
J 2
(-735 3660);
DISPLAY 0.680851 (-735 3660);
PAINT MONO (-735 3660);
FORCEPROP 2 LASTPIN (-225 3650) $PN 2
J 0
(-215 3660);
DISPLAY 0.680851 (-215 3660);
PAINT MONO (-215 3660);
FORCEPROP 2 LASTPIN (-775 3600) $PN 3
J 2
(-735 3610);
DISPLAY 0.680851 (-735 3610);
PAINT MONO (-735 3610);
FORCEPROP 2 LASTPIN (-225 3600) $PN 4
J 0
(-215 3610);
DISPLAY 0.680851 (-215 3610);
PAINT MONO (-215 3610);
FORCEPROP 2 LASTPIN (-775 3550) $PN 5
J 2
(-735 3560);
DISPLAY 0.680851 (-735 3560);
PAINT MONO (-735 3560);
FORCEPROP 2 LASTPIN (-225 3550) $PN 6
J 0
(-215 3560);
DISPLAY 0.680851 (-215 3560);
PAINT MONO (-215 3560);
FORCEPROP 2 LASTPIN (-775 3500) $PN 7
J 2
(-735 3510);
DISPLAY 0.680851 (-735 3510);
PAINT MONO (-735 3510);
FORCEPROP 2 LASTPIN (-225 3500) $PN 8
J 0
(-215 3510);
DISPLAY 0.680851 (-215 3510);
PAINT MONO (-215 3510);
FORCEPROP 2 LAST VALUE SCONN8_G802M0083150RD3HR
J 0
(-925 3850);
DISPLAY 0.680851 (-925 3850);
FORCEPROP 1 LAST MATERIAL IO
J 0
(-769 3707);
DISPLAY 0.723404 (-769 3707);
PAINT GREEN (-769 3707);
FORCEPROP 2 LAST PART_TYPE SMLF
J 0
(-775 3900);
DISPLAY 0.680851 (-775 3900);
FORCEPROP 2 LAST CDS_LIB pure_quanta
J 0
(-500 3575);
DISPLAY INVISIBLE (-500 3575);
FORCEPROP 1 LAST NEEDS_NO_SIZE TRUE
J 0
(-500 3575);
DISPLAY 0.723404 (-500 3575);
PAINT GREEN (-500 3575);
DISPLAY INVISIBLE (-500 3575);
FORCEPROP 1 LAST CDS_LMAN_SYM_OUTLINE -125,125,125,-125
J 0
(-500 3575);
DISPLAY 0.468085 (-500 3575);
PAINT GREEN (-500 3575);
DISPLAY INVISIBLE (-500 3575);
FORCEPROP 2 LAST SEC_TYPE 
J 0
(-625 3950);
DISPLAY 0.680851 (-625 3950);
DISPLAY INVISIBLE (-625 3950);
FORCEPROP 1 LAST PATH I418
J 0
(-500 3575);
DISPLAY 0.723404 (-500 3575);
PAINT GREEN (-500 3575);
DISPLAY INVISIBLE (-500 3575);
FORCEPROP 1 LAST PART_NUMBER DFHD08MS385
J 0
(-775 3750);
DISPLAY 0.723404 (-775 3750);
PAINT GREEN (-775 3750);
DISPLAY INVISIBLE (-775 3750);
FORCEADD SCONN8_G802M0083150RD3HR..1
(-1025 2525);
FORCEPROP 1 LAST LOCATION J49
J 0
(-1150 2750);
DISPLAY 0.723404 (-1150 2750);
PAINT GREEN (-1150 2750);
FORCEPROP 2 LAST SEC 1
J 0
(-1150 2900);
DISPLAY 0.680851 (-1150 2900);
PAINT MONO (-1150 2900);
DISPLAY INVISIBLE (-1150 2900);
FORCEPROP 2 LASTPIN (-1300 2600) $PN 1
J 2
(-1310 2610);
DISPLAY 0.680851 (-1310 2610);
PAINT MONO (-1310 2610);
FORCEPROP 2 LASTPIN (-750 2600) $PN 2
J 0
(-740 2610);
DISPLAY 0.680851 (-740 2610);
PAINT MONO (-740 2610);
FORCEPROP 2 LASTPIN (-1300 2550) $PN 3
J 2
(-1310 2560);
DISPLAY 0.680851 (-1310 2560);
PAINT MONO (-1310 2560);
FORCEPROP 2 LASTPIN (-750 2550) $PN 4
J 0
(-740 2560);
DISPLAY 0.680851 (-740 2560);
PAINT MONO (-740 2560);
FORCEPROP 2 LASTPIN (-1300 2500) $PN 5
J 2
(-1310 2510);
DISPLAY 0.680851 (-1310 2510);
PAINT MONO (-1310 2510);
FORCEPROP 2 LASTPIN (-750 2500) $PN 6
J 0
(-740 2510);
DISPLAY 0.680851 (-740 2510);
PAINT MONO (-740 2510);
FORCEPROP 2 LASTPIN (-1300 2450) $PN 7
J 2
(-1310 2460);
DISPLAY 0.680851 (-1310 2460);
PAINT MONO (-1310 2460);
FORCEPROP 2 LASTPIN (-750 2450) $PN 8
J 0
(-740 2460);
DISPLAY 0.680851 (-740 2460);
PAINT MONO (-740 2460);
FORCEPROP 1 LAST MATERIAL IO
J 0
(-1144 2657);
DISPLAY 0.723404 (-1144 2657);
PAINT GREEN (-1144 2657);
FORCEPROP 2 LAST PART_TYPE SMLF
J 0
(-1150 2850);
DISPLAY 0.680851 (-1150 2850);
FORCEPROP 2 LAST VALUE SCONN8_G802M0083150RD3HR
J 0
(-1150 2800);
DISPLAY 0.680851 (-1150 2800);
FORCEPROP 2 LAST SEC_TYPE 
J 0
(-1150 2900);
DISPLAY 0.680851 (-1150 2900);
DISPLAY INVISIBLE (-1150 2900);
FORCEPROP 1 LAST CDS_LMAN_SYM_OUTLINE -125,125,125,-125
J 0
(-1025 2525);
DISPLAY 0.468085 (-1025 2525);
PAINT GREEN (-1025 2525);
DISPLAY INVISIBLE (-1025 2525);
FORCEPROP 1 LAST NEEDS_NO_SIZE TRUE
J 0
(-1025 2525);
DISPLAY 0.723404 (-1025 2525);
PAINT GREEN (-1025 2525);
DISPLAY INVISIBLE (-1025 2525);
FORCEPROP 2 LAST CDS_LIB pure_quanta
J 0
(-1025 2525);
DISPLAY INVISIBLE (-1025 2525);
FORCEPROP 1 LAST PATH I419
J 0
(-1025 2525);
DISPLAY 0.723404 (-1025 2525);
PAINT GREEN (-1025 2525);
DISPLAY INVISIBLE (-1025 2525);
FORCEPROP 1 LAST PART_NUMBER DFHD08MS385
J 0
(-1150 2700);
DISPLAY 0.723404 (-1150 2700);
PAINT GREEN (-1150 2700);
DISPLAY INVISIBLE (-1150 2700);
FORCEADD Q_RES..1
(-500 5825);
FORCEPROP 1 LAST LOCATION R536
J 0
(-750 5825);
DISPLAY 0.510638 (-750 5825);
FORCEPROP 0 LAST $SEC 1
J 0
(-250 5850);
DISPLAY 0.680851 (-250 5850);
PAINT MONO (-250 5850);
DISPLAY INVISIBLE (-250 5850);
FORCEPROP 0 LAST CDS_SEC 1
J 0
(-250 5850);
DISPLAY 0.680851 (-250 5850);
DISPLAY INVISIBLE (-250 5850);
FORCEPROP 1 LASTPIN (-600 5825) $PN 1
J 0
(-588 5837);
DISPLAY 0.787234 (-588 5837);
PAINT MONO (-588 5837);
FORCEPROP 1 LASTPIN (-400 5825) $PN 2
J 0
(-438 5837);
DISPLAY 0.787234 (-438 5837);
PAINT MONO (-438 5837);
FORCEPROP 1 LAST MATERIAL EMPTY
J 0
(-875 5825);
DISPLAY 0.510638 (-875 5825);
PAINT RED (-875 5825);
FORCEPROP 1 LAST VALUE 2.2K
J 2
(-250 5825);
DISPLAY 0.510638 (-250 5825);
FORCEPROP 1 LAST PACK_TYPE 0402LF
J 0
(-250 5675);
DISPLAY 0.978723 (-250 5675);
DISPLAY INVISIBLE (-250 5675);
FORCEPROP 1 LAST WATTAGE 1/16W
J 2
(-525 5675);
DISPLAY 0.978723 (-525 5675);
DISPLAY INVISIBLE (-525 5675);
FORCEPROP 1 LAST TOLERANCE 5%
J 0
(-500 5725);
DISPLAY 0.978723 (-500 5725);
DISPLAY INVISIBLE (-500 5725);
FORCEPROP 2 LAST CDS_LIB pure_quanta
J 0
(-500 5825);
DISPLAY INVISIBLE (-500 5825);
FORCEPROP 1 LAST PATH I421
J 0
(-550 5975);
DISPLAY 0.978723 (-550 5975);
PAINT WHITE (-550 5975);
DISPLAY INVISIBLE (-550 5975);
FORCEPROP 1 LAST PART_NUMBER CS22202JB07
J 0
(-550 5925);
DISPLAY 0.978723 (-550 5925);
DISPLAY INVISIBLE (-550 5925);
FORCEADD DNS..2
(-525 5825);
PAINT RED (-525 5825);
FORCEPROP 2 LAST CDS_LIB mstr_misc
J 0
(-525 5825);
DISPLAY INVISIBLE (-525 5825);
FORCEPROP 1 LAST COMMENT_BODY TRUE
J 0
(-525 5825);
PAINT RED (-525 5825);
DISPLAY INVISIBLE (-525 5825);
FORCEADD DNS..2
(-8775 4400);
PAINT RED (-8775 4400);
FORCEPROP 2 LAST CDS_LIB mstr_misc
J 0
(-8775 4400);
DISPLAY INVISIBLE (-8775 4400);
FORCEPROP 1 LAST COMMENT_BODY TRUE
J 0
(-8775 4400);
PAINT RED (-8775 4400);
DISPLAY INVISIBLE (-8775 4400);
FORCEADD QUANTA_TITLE_BLOCK_C..1
(0 0);
FORCEPROP 0 LAST CDS_CON_LAST_MODIFIED Thu Sep 14 16:11:59 2023
J 0
(-1885 15);
DISPLAY INVISIBLE (-1885 15);
FORCEPROP 1 LAST CUSTOM_TXT_CDS <CON_LAST_MODIFIED>
J 0
(-1885 15);
DISPLAY 0.978723 (-1885 15);
FORCEPROP 2 LAST CUSTOM_TXT_CDS <XR_PAGE_TITLE>
J 0
(-7890 5250);
DISPLAY 0.638298 (-7890 5250);
PAINT PINK (-7890 5250);
DISPLAY INVISIBLE (-7890 5250);
FORCEPROP 1 LAST CUSTOM_TXT_CDS <NAME_2>
J 0
(-3175 50);
FORCEPROP 1 LAST CUSTOM_TXT_CDS <NAME_1>
J 0
(-3175 175);
FORCEPROP 1 LAST CUSTOM_TXT_CDS <Q_NUMBER>
J 0
(-1403 103);
DISPLAY 1.212766 (-1403 103);
FORCEPROP 1 LAST CUSTOM_TXT_CDS <Q_PROJ>
J 0
(-2382 102);
DISPLAY 1.212766 (-2382 102);
FORCEPROP 1 LAST CUSTOM_TXT_CDS <Q_REV>
J 0
(-184 103);
DISPLAY 1.212766 (-184 103);
FORCEPROP 1 LAST CUSTOM_TXT_CDS <CON_PAGE_NUM> OF <CON_TOTAL_PAGES>
J 0
(-446 18);
DISPLAY 0.978723 (-446 18);
FORCEPROP 1 LAST Q_TITLE CPU1 MISC 1/2
J 0
(-9275 50);
DISPLAY 2.446809 (-9275 50);
PAINT GREEN (-9275 50);
FORCEPROP 2 LAST PAGE_BORDER TRUE
J 0
(-7890 5250);
DISPLAY 0.638298 (-7890 5250);
PAINT PINK (-7890 5250);
DISPLAY INVISIBLE (-7890 5250);
FORCEPROP 1 LAST CDS_LMAN_SYM_OUTLINE -9475,6775,100,-125
J 0
(0 0);
DISPLAY 0.468085 (0 0);
PAINT GREEN (0 0);
DISPLAY INVISIBLE (0 0);
FORCEPROP 2 LAST CDS_LIB pure_quanta
J 0
(0 0);
DISPLAY INVISIBLE (0 0);
FORCEPROP 2 LAST CDS_XR_PAGE_TITLE CR-54 : @T6G_MB_LIB.T6G(SCH_1):PAGE54
J 0
(-7890 5250);
DISPLAY 0.638298 (-7890 5250);
PAINT PINK (-7890 5250);
DISPLAY INVISIBLE (-7890 5250);
FORCEPROP 1 LAST Q_DEPT BU9
J 1
(-3763 49);
DISPLAY 1.957447 (-3763 49);
PAINT GREEN (-3763 49);
DISPLAY INVISIBLE (-3763 49);
FORCEPROP 1 LAST COMMENT_BODY TRUE
J 0
(12 -13);
DISPLAY 0.978723 (12 -13);
PAINT GREEN (12 -13);
DISPLAY INVISIBLE (12 -13);
FORCEADD DNS..2
(-6750 600);
PAINT RED (-6750 600);
FORCEPROP 2 LAST CDS_LIB mstr_misc
J 0
(-6750 600);
DISPLAY INVISIBLE (-6750 600);
FORCEPROP 1 LAST COMMENT_BODY TRUE
J 0
(-6750 600);
PAINT RED (-6750 600);
DISPLAY INVISIBLE (-6750 600);
FORCEADD DNS..2
(-8300 600);
PAINT RED (-8300 600);
FORCEPROP 2 LAST CDS_LIB mstr_misc
J 0
(-8300 600);
PAINT MONO (-8300 600);
DISPLAY INVISIBLE (-8300 600);
FORCEPROP 1 LAST COMMENT_BODY TRUE
J 0
(-8300 600);
PAINT RED (-8300 600);
DISPLAY INVISIBLE (-8300 600);
FORCEADD DNS..2
(-7325 600);
PAINT RED (-7325 600);
FORCEPROP 2 LAST CDS_LIB mstr_misc
J 0
(-7325 600);
DISPLAY INVISIBLE (-7325 600);
FORCEPROP 1 LAST COMMENT_BODY TRUE
J 0
(-7325 600);
PAINT RED (-7325 600);
DISPLAY INVISIBLE (-7325 600);
FORCEADD DNS..2
(-7000 600);
PAINT RED (-7000 600);
FORCEPROP 2 LAST CDS_LIB mstr_misc
J 0
(-7000 600);
DISPLAY INVISIBLE (-7000 600);
FORCEPROP 1 LAST COMMENT_BODY TRUE
J 0
(-7000 600);
PAINT RED (-7000 600);
DISPLAY INVISIBLE (-7000 600);
FORCEADD DNS..2
(-7650 600);
PAINT RED (-7650 600);
FORCEPROP 2 LAST CDS_LIB mstr_misc
J 0
(-7650 600);
DISPLAY INVISIBLE (-7650 600);
FORCEPROP 1 LAST COMMENT_BODY TRUE
J 0
(-7650 600);
PAINT RED (-7650 600);
DISPLAY INVISIBLE (-7650 600);
FORCEADD DNS..2
(-7975 600);
PAINT RED (-7975 600);
FORCEPROP 2 LAST CDS_LIB mstr_misc
J 0
(-7975 600);
DISPLAY INVISIBLE (-7975 600);
FORCEPROP 1 LAST COMMENT_BODY TRUE
J 0
(-7975 600);
PAINT RED (-7975 600);
DISPLAY INVISIBLE (-7975 600);
WIRE 16 -1 (-5650 1375)(-5400 1375);
WIRE 16 -1 (-5650 1375)(-5650 1275);
WIRE 16 -1 (-8750 4925)(-8750 4950);
WIRE 16 -1 (-8625 4375)(-8625 4325);
WIRE 16 -1 (-8750 4375)(-8750 4325);
WIRE 16 -1 (-6725 525)(-6725 375);
WIRE 16 -1 (-7000 525)(-7000 375);
WIRE 16 -1 (-7300 525)(-7300 375);
WIRE 16 -1 (-7625 525)(-7625 375);
WIRE 16 -1 (-7950 525)(-7950 375);
WIRE 16 -1 (-8275 525)(-8275 375);
WIRE 16 -1 (-600 6075)(-1350 6075);
FORCEPROP 2 LAST SIG_NAME CPU1_BP0
J 0
(-1300 6085);
DISPLAY 0.489362 (-1300 6085);
WIRE 16 -1 (-600 6025)(-1350 6025);
FORCEPROP 2 LAST SIG_NAME CPU1_BP1
J 0
(-1300 6035);
DISPLAY 0.489362 (-1300 6035);
WIRE 16 -1 (-600 5925)(-1350 5925);
FORCEPROP 2 LAST SIG_NAME CPU1_BP3
J 0
(-1300 5935);
DISPLAY 0.489362 (-1300 5935);
WIRE 16 -1 (-400 5575)(-150 5575);
WIRE 16 -1 (-150 5575)(-150 5625);
WIRE 16 -1 (-150 5625)(-150 5675);
WIRE 16 -1 (-400 5625)(-150 5625);
WIRE 16 -1 (-150 5675)(-150 5725);
WIRE 16 -1 (-400 5675)(-150 5675);
WIRE 16 -1 (-150 5725)(-150 5775);
WIRE 16 -1 (-400 5725)(-150 5725);
WIRE 16 -1 (-150 5775)(-150 5825);
WIRE 16 -1 (-400 5775)(-150 5775);
WIRE 16 -1 (-150 5825)(-150 5875);
WIRE 16 -1 (-400 5825)(-150 5825);
WIRE 16 -1 (-150 5875)(-150 5925);
WIRE 16 -1 (-400 5875)(-150 5875);
WIRE 16 -1 (-150 5925)(-150 5975);
WIRE 16 -1 (-400 5925)(-150 5925);
WIRE 16 -1 (-150 5975)(-150 6025);
WIRE 16 -1 (-400 5975)(-150 5975);
WIRE 16 -1 (-150 6025)(-150 6075);
WIRE 16 -1 (-400 6025)(-150 6025);
WIRE 16 -1 (-150 6175)(-150 6075);
WIRE 16 -1 (-400 6075)(-150 6075);
WIRE 16 -1 (-600 5875)(-1350 5875);
FORCEPROP 2 LAST SIG_NAME APML_CPU1_ALERT_N
J 0
(-1300 5885);
DISPLAY 0.489362 (-1300 5885);
WIRE 16 -1 (-600 5975)(-1350 5975);
FORCEPROP 2 LAST SIG_NAME CPU1_BP2
J 0
(-1300 5985);
DISPLAY 0.489362 (-1300 5985);
WIRE 16 -1 (-8850 3325)(-9050 3325);
WIRE 16 -1 (-9050 3550)(-9050 3325);
WIRE 16 -1 (-9050 3325)(-9050 3275);
WIRE 16 -1 (-9050 3275)(-8850 3275);
WIRE 16 -1 (-9050 3275)(-9050 3225);
WIRE 16 -1 (-9050 3225)(-8850 3225);
WIRE 16 -1 (-9050 3225)(-9050 3175);
WIRE 16 -1 (-9050 3175)(-8850 3175);
WIRE 16 -1 (-9050 3175)(-9050 3125);
WIRE 16 -1 (-9050 3125)(-8850 3125);
WIRE 16 -1 (-9050 3125)(-9050 3075);
WIRE 16 -1 (-9050 3075)(-8850 3075);
WIRE 16 -1 (-9050 3075)(-9050 3025);
WIRE 16 -1 (-9050 3025)(-8850 3025);
WIRE 16 -1 (-225 3650)(-150 3650);
WIRE 16 -1 (-150 3650)(-150 3600);
WIRE 16 -1 (-225 3600)(-150 3600);
WIRE 16 -1 (-150 3600)(-150 3550);
WIRE 16 -1 (-150 3550)(-150 3500);
WIRE 16 -1 (-225 3550)(-150 3550);
WIRE 16 -1 (-225 3500)(-150 3500);
WIRE 16 -1 (-150 3500)(-150 3400);
WIRE 16 -1 (-750 2600)(-675 2600);
WIRE 16 -1 (-675 2600)(-675 2550);
WIRE 16 -1 (-675 2550)(-675 2500);
WIRE 16 -1 (-750 2550)(-675 2550);
WIRE 16 -1 (-675 2500)(-675 2450);
WIRE 16 -1 (-750 2500)(-675 2500);
WIRE 16 -1 (-750 2450)(-675 2450);
WIRE 16 -1 (-675 2450)(-675 2350);
WIRE 16 -1 (-8275 1500)(-7950 1500);
WIRE 16 -1 (-8275 1550)(-8275 1500);
WIRE 16 -1 (-8275 1500)(-8275 1425);
WIRE 16 -1 (-7950 1500)(-7625 1500);
WIRE 16 -1 (-7950 1425)(-7950 1500);
WIRE 16 -1 (-7625 1500)(-7300 1500);
WIRE 16 -1 (-7625 1425)(-7625 1500);
WIRE 16 -1 (-7300 1500)(-7000 1500);
WIRE 16 -1 (-7300 1425)(-7300 1500);
WIRE 16 -1 (-7000 1500)(-6725 1500);
WIRE 16 -1 (-7000 1500)(-7000 1425);
WIRE 16 -1 (-6725 1500)(-6725 1425);
WIRE 16 -1 (-600 5625)(-1350 5625);
FORCEPROP 2 LAST SIG_NAME CPU1_XTRIG_L7
J 0
(-1300 5635);
DISPLAY 0.489362 (-1300 5635);
WIRE 16 -1 (-1350 5575)(-600 5575);
FORCEPROP 2 LAST SIG_NAME CPU1_PROCHOT_N
J 0
(-1300 5585);
DISPLAY 0.489362 (-1300 5585);
WIRE 16 -1 (-600 5725)(-1350 5725);
FORCEPROP 2 LAST SIG_NAME CPU1_XTRIG_L5
J 0
(-1300 5735);
DISPLAY 0.489362 (-1300 5735);
WIRE 16 -1 (-600 5775)(-1350 5775);
FORCEPROP 2 LAST SIG_NAME CPU1_XTRIG_L4
J 0
(-1300 5785);
DISPLAY 0.489362 (-1300 5785);
WIRE 16 -1 (-600 5675)(-1350 5675);
FORCEPROP 2 LAST SIG_NAME CPU1_XTRIG_L6
J 0
(-1300 5685);
DISPLAY 0.489362 (-1300 5685);
WIRE 16 -1 (-600 5825)(-1350 5825);
FORCEPROP 2 LAST SIG_NAME CPU1_THERMTRIP_N
J 0
(-1300 5835);
DISPLAY 0.489362 (-1300 5835);
WIRE 16 -1 (-8650 3325)(-7800 3325);
FORCEPROP 2 LAST SIG_NAME CPU1_SP5R1
J 0
(-8300 3335);
DISPLAY 0.489362 (-8300 3335);
WIRE 16 -1 (-6600 2875)(-5400 2875);
FORCEPROP 2 LAST SIG_NAME CPU1_SP5R4
J 2
(-6260 2885);
DISPLAY 0.489362 (-6260 2885);
WIRE 16 -1 (-3900 4025)(-3125 4025);
FORCEPROP 2 LAST SIG_NAME TP_CPU1_TEST6_CCD2
J 0
(-3665 4035);
DISPLAY 0.489362 (-3665 4035);
FORCEPROP 2 LASTPROP $XRERR UNIQUE?
J 0
(-3095 4025);
DISPLAY 0.638298 (-3095 4025);
PAINT MONO (-3095 4025);
DISPLAY INVISIBLE (-3095 4025);
WIRE 16 -1 (-3900 4125)(-3125 4125);
FORCEPROP 2 LAST SIG_NAME TP_CPU1_TEST6_CCD0
J 0
(-3665 4135);
DISPLAY 0.489362 (-3665 4135);
FORCEPROP 2 LASTPROP $XRERR UNIQUE?
J 0
(-3095 4125);
DISPLAY 0.638298 (-3095 4125);
PAINT MONO (-3095 4125);
DISPLAY INVISIBLE (-3095 4125);
WIRE 16 -1 (-3900 4375)(-3075 4375);
FORCEPROP 2 LAST SIG_NAME CPU1_BP2
J 0
(-3685 4385);
DISPLAY 0.489362 (-3685 4385);
WIRE 16 -1 (-3900 4475)(-3075 4475);
FORCEPROP 2 LAST SIG_NAME CPU1_BP0
J 0
(-3685 4485);
DISPLAY 0.489362 (-3685 4485);
WIRE 16 -1 (-3900 4675)(-3200 4675);
FORCEPROP 2 LAST SIG_NAME CPU1_XTRIG_R2_L7
J 0
(-3685 4685);
DISPLAY 0.489362 (-3685 4685);
FORCEPROP 2 LASTPROP $XRERR UNIQUE?
J 0
(-3925 4685);
DISPLAY 0.638298 (-3925 4685);
PAINT MONO (-3925 4685);
DISPLAY INVISIBLE (-3925 4685);
WIRE 16 -1 (-3900 4775)(-3200 4775);
FORCEPROP 2 LAST SIG_NAME CPU1_XTRIG_R2_L5
J 0
(-3685 4785);
DISPLAY 0.489362 (-3685 4785);
FORCEPROP 2 LASTPROP $XRERR UNIQUE?
J 0
(-3925 4785);
DISPLAY 0.638298 (-3925 4785);
PAINT MONO (-3925 4785);
DISPLAY INVISIBLE (-3925 4785);
WIRE 16 -1 (-3000 5125)(-2400 5125);
FORCEPROP 2 LAST SIG_NAME APML_CPU1_ALERT_R_N
J 0
(-2850 5135);
DISPLAY 0.489362 (-2850 5135);
WIRE 16 -1 (-6600 2775)(-5400 2775);
FORCEPROP 2 LAST SIG_NAME CPU1_CORETYPE0
J 2
(-6160 2785);
DISPLAY 0.489362 (-6160 2785);
WIRE 16 -1 (-5400 2525)(-6825 2525);
FORCEPROP 2 LAST SIG_NAME VSENSE_VSS_SENSE_B_P1
J 0
(-6120 2535);
DISPLAY 0.489362 (-6120 2535);
WIRE 16 -1 (-6825 2525)(-6975 2525);
WIRE 16 -1 (-6825 1950)(-6825 2525);
WIRE 16 -1 (-5400 2275)(-6475 2275);
FORCEPROP 2 LAST SIG_NAME VSENSE_PVDDCR_CPU1_P1_DP
J 0
(-6120 2285);
DISPLAY 0.489362 (-6120 2285);
WIRE 16 -1 (-6475 2275)(-6975 2275);
WIRE 16 -1 (-6475 2275)(-6475 1950);
WIRE 16 -1 (-3900 2925)(-3125 2925);
FORCEPROP 2 LAST SIG_NAME TP_CPU1_TEST4_CCD9
J 0
(-3665 2935);
DISPLAY 0.489362 (-3665 2935);
FORCEPROP 2 LASTPROP $XRERR UNIQUE?
J 0
(-3095 2925);
DISPLAY 0.638298 (-3095 2925);
PAINT MONO (-3095 2925);
DISPLAY INVISIBLE (-3095 2925);
WIRE 16 -1 (-3900 5025)(-2425 5025);
FORCEPROP 2 LAST SIG_NAME CPU1_PROCHOT_N
J 0
(-3700 5035);
DISPLAY 0.489362 (-3700 5035);
WIRE 16 -1 (-3900 5725)(-3125 5725);
FORCEPROP 2 LAST SIG_NAME NC_CPU1_AZ_SYNC
J 0
(-3690 5735);
DISPLAY 0.489362 (-3690 5735);
FORCEPROP 2 LASTPROP $XRERR UNIQUE?
J 0
(-3095 5725);
DISPLAY 0.638298 (-3095 5725);
PAINT MONO (-3095 5725);
DISPLAY INVISIBLE (-3095 5725);
WIRE 16 -1 (-3900 5925)(-3125 5925);
FORCEPROP 2 LAST SIG_NAME NC_CPU1_AZ_SDIN0
J 0
(-3690 5935);
DISPLAY 0.489362 (-3690 5935);
FORCEPROP 2 LASTPROP $XRERR UNIQUE?
J 0
(-3095 5925);
DISPLAY 0.638298 (-3095 5925);
PAINT MONO (-3095 5925);
DISPLAY INVISIBLE (-3095 5925);
WIRE 16 -1 (-3900 5975)(-3125 5975);
FORCEPROP 2 LAST SIG_NAME NC_CPU1_AZ_RST_N
J 0
(-3690 5985);
DISPLAY 0.489362 (-3690 5985);
FORCEPROP 2 LASTPROP $XRERR UNIQUE?
J 0
(-3095 5975);
DISPLAY 0.638298 (-3095 5975);
PAINT MONO (-3095 5975);
DISPLAY INVISIBLE (-3095 5975);
WIRE 16 -1 (-3900 5875)(-3125 5875);
FORCEPROP 2 LAST SIG_NAME NC_CPU1_AZ_SDIN1
J 0
(-3690 5885);
DISPLAY 0.489362 (-3690 5885);
FORCEPROP 2 LASTPROP $XRERR UNIQUE?
J 0
(-3095 5875);
DISPLAY 0.638298 (-3095 5875);
PAINT MONO (-3095 5875);
DISPLAY INVISIBLE (-3095 5875);
WIRE 16 -1 (-3900 5775)(-3125 5775);
FORCEPROP 2 LAST SIG_NAME NC_CPU1_AZ_SDOUT
J 0
(-3690 5785);
DISPLAY 0.489362 (-3690 5785);
FORCEPROP 2 LASTPROP $XRERR UNIQUE?
J 0
(-3095 5775);
DISPLAY 0.638298 (-3095 5775);
PAINT MONO (-3095 5775);
DISPLAY INVISIBLE (-3095 5775);
WIRE 16 -1 (-3900 5825)(-3125 5825);
FORCEPROP 2 LAST SIG_NAME NC_CPU1_AZ_SDIN2
J 0
(-3690 5835);
DISPLAY 0.489362 (-3690 5835);
FORCEPROP 2 LASTPROP $XRERR UNIQUE?
J 0
(-3095 5825);
DISPLAY 0.638298 (-3095 5825);
PAINT MONO (-3095 5825);
DISPLAY INVISIBLE (-3095 5825);
WIRE 16 -1 (-3900 6025)(-3125 6025);
FORCEPROP 2 LAST SIG_NAME NC_CPU1_AZ_BITCLK
J 0
(-3690 6035);
DISPLAY 0.489362 (-3690 6035);
FORCEPROP 2 LASTPROP $XRERR UNIQUE?
J 0
(-3095 6025);
DISPLAY 0.638298 (-3095 6025);
PAINT MONO (-3095 6025);
DISPLAY INVISIBLE (-3095 6025);
WIRE 16 -1 (-3900 4325)(-3075 4325);
FORCEPROP 2 LAST SIG_NAME CPU1_BP3
J 0
(-3685 4335);
DISPLAY 0.489362 (-3685 4335);
WIRE 16 -1 (-3900 4425)(-3075 4425);
FORCEPROP 2 LAST SIG_NAME CPU1_BP1
J 0
(-3685 4435);
DISPLAY 0.489362 (-3685 4435);
WIRE 16 -1 (-3900 3675)(-3125 3675);
FORCEPROP 2 LAST SIG_NAME TP_CPU1_TEST6_X3D3
J 0
(-3665 3685);
DISPLAY 0.489362 (-3665 3685);
FORCEPROP 2 LASTPROP $XRERR UNIQUE?
J 0
(-3095 3675);
DISPLAY 0.638298 (-3095 3675);
PAINT MONO (-3095 3675);
DISPLAY INVISIBLE (-3095 3675);
WIRE 16 -1 (-3900 3725)(-3125 3725);
FORCEPROP 2 LAST SIG_NAME TP_CPU1_TEST6_X3D2
J 0
(-3665 3735);
DISPLAY 0.489362 (-3665 3735);
FORCEPROP 2 LASTPROP $XRERR UNIQUE?
J 0
(-3095 3725);
DISPLAY 0.638298 (-3095 3725);
PAINT MONO (-3095 3725);
DISPLAY INVISIBLE (-3095 3725);
WIRE 16 -1 (-3900 3775)(-3125 3775);
FORCEPROP 2 LAST SIG_NAME TP_CPU1_TEST6_X3D1
J 0
(-3665 3785);
DISPLAY 0.489362 (-3665 3785);
FORCEPROP 2 LASTPROP $XRERR UNIQUE?
J 0
(-3095 3775);
DISPLAY 0.638298 (-3095 3775);
PAINT MONO (-3095 3775);
DISPLAY INVISIBLE (-3095 3775);
WIRE 16 -1 (-3900 3825)(-3125 3825);
FORCEPROP 2 LAST SIG_NAME TP_CPU1_TEST6_X3D0
J 0
(-3665 3835);
DISPLAY 0.489362 (-3665 3835);
FORCEPROP 2 LASTPROP $XRERR UNIQUE?
J 0
(-3095 3825);
DISPLAY 0.638298 (-3095 3825);
PAINT MONO (-3095 3825);
DISPLAY INVISIBLE (-3095 3825);
WIRE 16 -1 (-3900 3075)(-3125 3075);
FORCEPROP 2 LAST SIG_NAME TP_CPU1_TEST4_CCD6
J 0
(-3665 3085);
DISPLAY 0.489362 (-3665 3085);
FORCEPROP 2 LASTPROP $XRERR UNIQUE?
J 0
(-3095 3075);
DISPLAY 0.638298 (-3095 3075);
PAINT MONO (-3095 3075);
DISPLAY INVISIBLE (-3095 3075);
WIRE 16 -1 (-3900 3125)(-3125 3125);
FORCEPROP 2 LAST SIG_NAME TP_CPU1_TEST4_CCD5
J 0
(-3665 3135);
DISPLAY 0.489362 (-3665 3135);
FORCEPROP 2 LASTPROP $XRERR UNIQUE?
J 0
(-3095 3125);
DISPLAY 0.638298 (-3095 3125);
PAINT MONO (-3095 3125);
DISPLAY INVISIBLE (-3095 3125);
WIRE 16 -1 (-3900 3175)(-3125 3175);
FORCEPROP 2 LAST SIG_NAME TP_CPU1_TEST4_CCD4
J 0
(-3665 3185);
DISPLAY 0.489362 (-3665 3185);
FORCEPROP 2 LASTPROP $XRERR UNIQUE?
J 0
(-3095 3175);
DISPLAY 0.638298 (-3095 3175);
PAINT MONO (-3095 3175);
DISPLAY INVISIBLE (-3095 3175);
WIRE 16 -1 (-3900 3475)(-3125 3475);
FORCEPROP 2 LAST SIG_NAME TP_CPU1_TEST6_IOD
J 0
(-3665 3485);
DISPLAY 0.489362 (-3665 3485);
FORCEPROP 2 LASTPROP $XRERR UNIQUE?
J 0
(-3095 3475);
DISPLAY 0.638298 (-3095 3475);
PAINT MONO (-3095 3475);
DISPLAY INVISIBLE (-3095 3475);
WIRE 16 -1 (-3900 3225)(-3125 3225);
FORCEPROP 2 LAST SIG_NAME TP_CPU1_TEST4_CCD3
J 0
(-3665 3235);
DISPLAY 0.489362 (-3665 3235);
FORCEPROP 2 LASTPROP $XRERR UNIQUE?
J 0
(-3095 3225);
DISPLAY 0.638298 (-3095 3225);
PAINT MONO (-3095 3225);
DISPLAY INVISIBLE (-3095 3225);
WIRE 16 -1 (-3900 3275)(-3125 3275);
FORCEPROP 2 LAST SIG_NAME TP_CPU1_TEST4_CCD2
J 0
(-3665 3285);
DISPLAY 0.489362 (-3665 3285);
FORCEPROP 2 LASTPROP $XRERR UNIQUE?
J 0
(-3095 3275);
DISPLAY 0.638298 (-3095 3275);
PAINT MONO (-3095 3275);
DISPLAY INVISIBLE (-3095 3275);
WIRE 16 -1 (-3900 3325)(-3125 3325);
FORCEPROP 2 LAST SIG_NAME TP_CPU1_TEST4_CCD1
J 0
(-3665 3335);
DISPLAY 0.489362 (-3665 3335);
FORCEPROP 2 LASTPROP $XRERR UNIQUE?
J 0
(-3095 3325);
DISPLAY 0.638298 (-3095 3325);
PAINT MONO (-3095 3325);
DISPLAY INVISIBLE (-3095 3325);
WIRE 16 -1 (-3900 3975)(-3125 3975);
FORCEPROP 2 LAST SIG_NAME TP_CPU1_TEST6_CCD3
J 0
(-3665 3985);
DISPLAY 0.489362 (-3665 3985);
FORCEPROP 2 LASTPROP $XRERR UNIQUE?
J 0
(-3095 3975);
DISPLAY 0.638298 (-3095 3975);
PAINT MONO (-3095 3975);
DISPLAY INVISIBLE (-3095 3975);
WIRE 16 -1 (-3900 3375)(-3125 3375);
FORCEPROP 2 LAST SIG_NAME TP_CPU1_TEST4_CCD0
J 0
(-3665 3385);
DISPLAY 0.489362 (-3665 3385);
FORCEPROP 2 LASTPROP $XRERR UNIQUE?
J 0
(-3095 3375);
DISPLAY 0.638298 (-3095 3375);
PAINT MONO (-3095 3375);
DISPLAY INVISIBLE (-3095 3375);
WIRE 16 -1 (-3900 3575)(-3125 3575);
FORCEPROP 2 LAST SIG_NAME TP_CPU1_TEST6_X3D5
J 0
(-3665 3585);
DISPLAY 0.489362 (-3665 3585);
FORCEPROP 2 LASTPROP $XRERR UNIQUE?
J 0
(-3095 3575);
DISPLAY 0.638298 (-3095 3575);
PAINT MONO (-3095 3575);
DISPLAY INVISIBLE (-3095 3575);
WIRE 16 -1 (-3900 4075)(-3125 4075);
FORCEPROP 2 LAST SIG_NAME TP_CPU1_TEST6_CCD1
J 0
(-3665 4085);
DISPLAY 0.489362 (-3665 4085);
FORCEPROP 2 LASTPROP $XRERR UNIQUE?
J 0
(-3095 4075);
DISPLAY 0.638298 (-3095 4075);
PAINT MONO (-3095 4075);
DISPLAY INVISIBLE (-3095 4075);
WIRE 16 -1 (-3900 3625)(-3125 3625);
FORCEPROP 2 LAST SIG_NAME TP_CPU1_TEST6_X3D4
J 0
(-3665 3635);
DISPLAY 0.489362 (-3665 3635);
FORCEPROP 2 LASTPROP $XRERR UNIQUE?
J 0
(-3095 3625);
DISPLAY 0.638298 (-3095 3625);
PAINT MONO (-3095 3625);
DISPLAY INVISIBLE (-3095 3625);
WIRE 16 -1 (-3900 2175)(-3125 2175);
FORCEPROP 2 LAST SIG_NAME TP_CPU1_TEST5_CCD11
J 0
(-3665 2185);
DISPLAY 0.489362 (-3665 2185);
FORCEPROP 2 LASTPROP $XRERR UNIQUE?
J 0
(-3095 2175);
DISPLAY 0.638298 (-3095 2175);
PAINT MONO (-3095 2175);
DISPLAY INVISIBLE (-3095 2175);
WIRE 16 -1 (-3900 2825)(-3125 2825);
FORCEPROP 2 LAST SIG_NAME TP_CPU1_TEST4_CCD11
J 0
(-3665 2835);
DISPLAY 0.489362 (-3665 2835);
FORCEPROP 2 LASTPROP $XRERR UNIQUE?
J 0
(-3095 2825);
DISPLAY 0.638298 (-3095 2825);
PAINT MONO (-3095 2825);
DISPLAY INVISIBLE (-3095 2825);
WIRE 16 -1 (-3125 2225)(-3900 2225);
FORCEPROP 2 LAST SIG_NAME TP_CPU1_TEST5_CCD10
J 0
(-3665 2235);
DISPLAY 0.489362 (-3665 2235);
FORCEPROP 2 LASTPROP $XRERR UNIQUE?
J 0
(-3095 2225);
DISPLAY 0.638298 (-3095 2225);
PAINT MONO (-3095 2225);
DISPLAY INVISIBLE (-3095 2225);
WIRE 16 -1 (-3900 2875)(-3125 2875);
FORCEPROP 2 LAST SIG_NAME TP_CPU1_TEST4_CCD10
J 0
(-3665 2885);
DISPLAY 0.489362 (-3665 2885);
FORCEPROP 2 LASTPROP $XRERR UNIQUE?
J 0
(-3095 2875);
DISPLAY 0.638298 (-3095 2875);
PAINT MONO (-3095 2875);
DISPLAY INVISIBLE (-3095 2875);
WIRE 16 -1 (-3900 2975)(-3125 2975);
FORCEPROP 2 LAST SIG_NAME TP_CPU1_TEST4_CCD8
J 0
(-3665 2985);
DISPLAY 0.489362 (-3665 2985);
FORCEPROP 2 LASTPROP $XRERR UNIQUE?
J 0
(-3095 2975);
DISPLAY 0.638298 (-3095 2975);
PAINT MONO (-3095 2975);
DISPLAY INVISIBLE (-3095 2975);
WIRE 16 -1 (-3900 2275)(-3125 2275);
FORCEPROP 2 LAST SIG_NAME TP_CPU1_TEST5_CCD9
J 0
(-3665 2285);
DISPLAY 0.489362 (-3665 2285);
FORCEPROP 2 LASTPROP $XRERR UNIQUE?
J 0
(-3095 2275);
DISPLAY 0.638298 (-3095 2275);
PAINT MONO (-3095 2275);
DISPLAY INVISIBLE (-3095 2275);
WIRE 16 -1 (-3900 3025)(-3125 3025);
FORCEPROP 2 LAST SIG_NAME TP_CPU1_TEST4_CCD7
J 0
(-3665 3035);
DISPLAY 0.489362 (-3665 3035);
FORCEPROP 2 LASTPROP $XRERR UNIQUE?
J 0
(-3095 3025);
DISPLAY 0.638298 (-3095 3025);
PAINT MONO (-3095 3025);
DISPLAY INVISIBLE (-3095 3025);
WIRE 16 -1 (-3900 2325)(-3125 2325);
FORCEPROP 2 LAST SIG_NAME TP_CPU1_TEST5_CCD8
J 0
(-3665 2335);
DISPLAY 0.489362 (-3665 2335);
FORCEPROP 2 LASTPROP $XRERR UNIQUE?
J 0
(-3095 2325);
DISPLAY 0.638298 (-3095 2325);
PAINT MONO (-3095 2325);
DISPLAY INVISIBLE (-3095 2325);
WIRE 16 -1 (-3900 2375)(-3125 2375);
FORCEPROP 2 LAST SIG_NAME TP_CPU1_TEST5_CCD7
J 0
(-3665 2385);
DISPLAY 0.489362 (-3665 2385);
FORCEPROP 2 LASTPROP $XRERR UNIQUE?
J 0
(-3095 2375);
DISPLAY 0.638298 (-3095 2375);
PAINT MONO (-3095 2375);
DISPLAY INVISIBLE (-3095 2375);
WIRE 16 -1 (-3900 2425)(-3125 2425);
FORCEPROP 2 LAST SIG_NAME TP_CPU1_TEST5_CCD6
J 0
(-3665 2435);
DISPLAY 0.489362 (-3665 2435);
FORCEPROP 2 LASTPROP $XRERR UNIQUE?
J 0
(-3095 2425);
DISPLAY 0.638298 (-3095 2425);
PAINT MONO (-3095 2425);
DISPLAY INVISIBLE (-3095 2425);
WIRE 16 -1 (-3900 2475)(-3125 2475);
FORCEPROP 2 LAST SIG_NAME TP_CPU1_TEST5_CCD5
J 0
(-3665 2485);
DISPLAY 0.489362 (-3665 2485);
FORCEPROP 2 LASTPROP $XRERR UNIQUE?
J 0
(-3095 2475);
DISPLAY 0.638298 (-3095 2475);
PAINT MONO (-3095 2475);
DISPLAY INVISIBLE (-3095 2475);
WIRE 16 -1 (-3900 2525)(-3125 2525);
FORCEPROP 2 LAST SIG_NAME TP_CPU1_TEST5_CCD4
J 0
(-3665 2535);
DISPLAY 0.489362 (-3665 2535);
FORCEPROP 2 LASTPROP $XRERR UNIQUE?
J 0
(-3095 2525);
DISPLAY 0.638298 (-3095 2525);
PAINT MONO (-3095 2525);
DISPLAY INVISIBLE (-3095 2525);
WIRE 16 -1 (-3125 2075)(-3900 2075);
FORCEPROP 2 LAST SIG_NAME TP_CPU1_TEST4_IOD
J 0
(-3665 2085);
DISPLAY 0.489362 (-3665 2085);
FORCEPROP 2 LASTPROP $XRERR UNIQUE?
J 0
(-3095 2075);
DISPLAY 0.638298 (-3095 2075);
PAINT MONO (-3095 2075);
DISPLAY INVISIBLE (-3095 2075);
WIRE 16 -1 (-3900 2575)(-3125 2575);
FORCEPROP 2 LAST SIG_NAME TP_CPU1_TEST5_CCD3
J 0
(-3665 2585);
DISPLAY 0.489362 (-3665 2585);
FORCEPROP 2 LASTPROP $XRERR UNIQUE?
J 0
(-3095 2575);
DISPLAY 0.638298 (-3095 2575);
PAINT MONO (-3095 2575);
DISPLAY INVISIBLE (-3095 2575);
WIRE 16 -1 (-3900 2625)(-3125 2625);
FORCEPROP 2 LAST SIG_NAME TP_CPU1_TEST5_CCD2
J 0
(-3665 2635);
DISPLAY 0.489362 (-3665 2635);
FORCEPROP 2 LASTPROP $XRERR UNIQUE?
J 0
(-3095 2625);
DISPLAY 0.638298 (-3095 2625);
PAINT MONO (-3095 2625);
DISPLAY INVISIBLE (-3095 2625);
WIRE 16 -1 (-3900 2675)(-3125 2675);
FORCEPROP 2 LAST SIG_NAME TP_CPU1_TEST5_CCD1
J 0
(-3665 2685);
DISPLAY 0.489362 (-3665 2685);
FORCEPROP 2 LASTPROP $XRERR UNIQUE?
J 0
(-3095 2675);
DISPLAY 0.638298 (-3095 2675);
PAINT MONO (-3095 2675);
DISPLAY INVISIBLE (-3095 2675);
WIRE 16 -1 (-3900 2725)(-3125 2725);
FORCEPROP 2 LAST SIG_NAME TP_CPU1_TEST5_CCD0
J 0
(-3665 2735);
DISPLAY 0.489362 (-3665 2735);
FORCEPROP 2 LASTPROP $XRERR UNIQUE?
J 0
(-3095 2725);
DISPLAY 0.638298 (-3095 2725);
PAINT MONO (-3095 2725);
DISPLAY INVISIBLE (-3095 2725);
WIRE 16 -1 (-3900 1575)(-2775 1575);
FORCEPROP 2 LAST SIG_NAME TP_CPU1_UART1_RX
J 0
(-3650 1585);
DISPLAY 0.489362 (-3650 1585);
FORCEPROP 2 LASTPROP $XRERR UNIQUE?
J 0
(-2745 1575);
DISPLAY 0.638298 (-2745 1575);
PAINT MONO (-2745 1575);
DISPLAY INVISIBLE (-2745 1575);
WIRE 16 -1 (-3900 1875)(-2775 1875);
FORCEPROP 2 LAST SIG_NAME TP_CPU1_UART0_CTS_N
J 0
(-3650 1885);
DISPLAY 0.489362 (-3650 1885);
FORCEPROP 2 LASTPROP $XRERR UNIQUE?
J 0
(-2745 1875);
DISPLAY 0.638298 (-2745 1875);
PAINT MONO (-2745 1875);
DISPLAY INVISIBLE (-2745 1875);
WIRE 16 -1 (-3900 1725)(-2775 1725);
FORCEPROP 2 LAST SIG_NAME TP_CPU1_UART0_TX
J 0
(-3650 1735);
DISPLAY 0.489362 (-3650 1735);
FORCEPROP 2 LASTPROP $XRERR UNIQUE?
J 0
(-2745 1725);
DISPLAY 0.638298 (-2745 1725);
PAINT MONO (-2745 1725);
DISPLAY INVISIBLE (-2745 1725);
WIRE 16 -1 (-3900 1825)(-2775 1825);
FORCEPROP 2 LAST SIG_NAME TP_CPU1_UART0_RTS_N
J 0
(-3650 1835);
DISPLAY 0.489362 (-3650 1835);
FORCEPROP 2 LASTPROP $XRERR UNIQUE?
J 0
(-2745 1825);
DISPLAY 0.638298 (-2745 1825);
PAINT MONO (-2745 1825);
DISPLAY INVISIBLE (-2745 1825);
WIRE 16 -1 (-3900 1675)(-2775 1675);
FORCEPROP 2 LAST SIG_NAME TP_CPU1_UART0_RX
J 0
(-3650 1685);
DISPLAY 0.489362 (-3650 1685);
FORCEPROP 2 LASTPROP $XRERR UNIQUE?
J 0
(-2745 1675);
DISPLAY 0.638298 (-2745 1675);
PAINT MONO (-2745 1675);
DISPLAY INVISIBLE (-2745 1675);
WIRE 16 -1 (-3900 1375)(-3125 1375);
FORCEPROP 2 LAST SIG_NAME TP_CPU1_TEST41_IOD
J 0
(-3665 1385);
DISPLAY 0.489362 (-3665 1385);
FORCEPROP 2 LASTPROP $XRERR UNIQUE?
J 0
(-3095 1375);
DISPLAY 0.638298 (-3095 1375);
PAINT MONO (-3095 1375);
DISPLAY INVISIBLE (-3095 1375);
WIRE 16 -1 (-3900 1975)(-3125 1975);
FORCEPROP 2 LAST SIG_NAME TP_CPU1_TEST5_IOD
J 0
(-3665 1985);
DISPLAY 0.489362 (-3665 1985);
FORCEPROP 2 LASTPROP $XRERR UNIQUE?
J 0
(-3095 1975);
DISPLAY 0.638298 (-3095 1975);
PAINT MONO (-3095 1975);
DISPLAY INVISIBLE (-3095 1975);
WIRE 16 -1 (-3900 1775)(-3125 1775);
FORCEPROP 2 LAST SIG_NAME TP_CPU1_UART0_INTR
J 0
(-3650 1785);
DISPLAY 0.489362 (-3650 1785);
FORCEPROP 2 LASTPROP $XRERR UNIQUE?
J 0
(-3095 1775);
DISPLAY 0.638298 (-3095 1775);
PAINT MONO (-3095 1775);
DISPLAY INVISIBLE (-3095 1775);
WIRE 16 -1 (-6050 5125)(-5400 5125);
FORCEPROP 2 LAST SIG_NAME SMB_APML_CPU1_SCL
J 2
(-5585 5135);
DISPLAY 0.489362 (-5585 5135);
WIRE 16 -1 (-6050 5075)(-5400 5075);
FORCEPROP 2 LAST SIG_NAME SMB_APML_CPU1_SDA
J 2
(-5585 5085);
DISPLAY 0.489362 (-5585 5085);
WIRE 16 -1 (-6800 4525)(-5400 4525);
FORCEPROP 2 LAST SIG_NAME JTAG_CPU1_DBREQ_N
J 0
(-6725 4535);
DISPLAY 0.489362 (-6725 4535);
WIRE 16 -1 (-6800 4625)(-5400 4625);
FORCEPROP 2 LAST SIG_NAME JTAG_CPU1_TMS
J 0
(-6725 4635);
DISPLAY 0.489362 (-6725 4635);
WIRE 16 -1 (-6800 4675)(-5400 4675);
FORCEPROP 2 LAST SIG_NAME JTAG_CPU1_TCK
J 0
(-6725 4685);
DISPLAY 0.489362 (-6725 4685);
WIRE 16 -1 (-6800 4725)(-5400 4725);
FORCEPROP 2 LAST SIG_NAME JTAG_CPU1_TRST_N
J 0
(-6725 4735);
DISPLAY 0.489362 (-6725 4735);
WIRE 16 -1 (-6800 4775)(-5400 4775);
FORCEPROP 2 LAST SIG_NAME JTAG_CPU1_TDI
J 0
(-6725 4785);
DISPLAY 0.489362 (-6725 4785);
WIRE 16 -1 (-6150 5675)(-5400 5675);
FORCEPROP 2 LAST SIG_NAME SVID_PVDDCR_CPU0_P1_SVTO
J 0
(-6125 5685);
DISPLAY 0.489362 (-6125 5685);
WIRE 16 -1 (-6150 5875)(-5400 5875);
FORCEPROP 2 LAST SIG_NAME FM_P1_PCC1_N
J 0
(-6110 5885);
DISPLAY 0.489362 (-6110 5885);
WIRE 16 -1 (-6600 2675)(-5400 2675);
FORCEPROP 2 LAST SIG_NAME CPU1_CORETYPE2
J 2
(-6160 2685);
DISPLAY 0.489362 (-6160 2685);
WIRE 16 -1 (-6600 2725)(-5400 2725);
FORCEPROP 2 LAST SIG_NAME CPU1_CORETYPE1
J 2
(-6160 2735);
DISPLAY 0.489362 (-6160 2735);
WIRE 16 -1 (-6600 2925)(-5400 2925);
FORCEPROP 2 LAST SIG_NAME CPU1_SP5R3
J 2
(-6260 2935);
DISPLAY 0.489362 (-6260 2935);
WIRE 16 -1 (-6600 2975)(-5400 2975);
FORCEPROP 2 LAST SIG_NAME CPU1_SP5R2
J 2
(-6260 2985);
DISPLAY 0.489362 (-6260 2985);
WIRE 16 -1 (-6600 3025)(-5400 3025);
FORCEPROP 2 LAST SIG_NAME CPU1_SP5R1
J 2
(-6260 3035);
DISPLAY 0.489362 (-6260 3035);
WIRE 16 -1 (-6600 3175)(-5400 3175);
FORCEPROP 2 LAST SIG_NAME CPU1_SA1
J 0
(-6485 3185);
DISPLAY 0.489362 (-6485 3185);
WIRE 16 -1 (-6600 3225)(-5400 3225);
FORCEPROP 2 LAST SIG_NAME CPU1_SA0
J 0
(-6485 3235);
DISPLAY 0.489362 (-6485 3235);
WIRE 16 -1 (-6600 3325)(-5400 3325);
FORCEPROP 2 LAST SIG_NAME PRSNT_CPU1_N
J 2
(-6210 3335);
DISPLAY 0.489362 (-6210 3335);
WIRE 16 -1 (-6525 3925)(-5400 3925);
FORCEPROP 2 LAST SIG_NAME TP_CPU1_TEST47_CCD3
J 0
(-6285 3935);
DISPLAY 0.489362 (-6285 3935);
FORCEPROP 2 LASTPROP $XRERR UNIQUE?
J 0
(-6765 3925);
DISPLAY 0.638298 (-6765 3925);
PAINT MONO (-6765 3925);
DISPLAY INVISIBLE (-6765 3925);
WIRE 16 -1 (-6525 3775)(-5400 3775);
FORCEPROP 2 LAST SIG_NAME TP_CPU1_TEST47_IOD1
J 0
(-6285 3785);
DISPLAY 0.489362 (-6285 3785);
FORCEPROP 2 LASTPROP $XRERR UNIQUE?
J 0
(-6765 3775);
DISPLAY 0.638298 (-6765 3775);
PAINT MONO (-6765 3775);
DISPLAY INVISIBLE (-6765 3775);
WIRE 16 -1 (-6525 3825)(-5400 3825);
FORCEPROP 2 LAST SIG_NAME TP_CPU1_TEST47_IOD0
J 0
(-6285 3835);
DISPLAY 0.489362 (-6285 3835);
FORCEPROP 2 LASTPROP $XRERR UNIQUE?
J 0
(-6765 3825);
DISPLAY 0.638298 (-6765 3825);
PAINT MONO (-6765 3825);
DISPLAY INVISIBLE (-6765 3825);
WIRE 16 -1 (-6525 3975)(-5400 3975);
FORCEPROP 2 LAST SIG_NAME TP_CPU1_TEST47_CCD2
J 0
(-6285 3985);
DISPLAY 0.489362 (-6285 3985);
FORCEPROP 2 LASTPROP $XRERR UNIQUE?
J 0
(-6765 3975);
DISPLAY 0.638298 (-6765 3975);
PAINT MONO (-6765 3975);
DISPLAY INVISIBLE (-6765 3975);
WIRE 16 -1 (-6525 4025)(-5400 4025);
FORCEPROP 2 LAST SIG_NAME TP_CPU1_TEST47_CCD1
J 0
(-6285 4035);
DISPLAY 0.489362 (-6285 4035);
FORCEPROP 2 LASTPROP $XRERR UNIQUE?
J 0
(-6765 4025);
DISPLAY 0.638298 (-6765 4025);
PAINT MONO (-6765 4025);
DISPLAY INVISIBLE (-6765 4025);
WIRE 16 -1 (-6525 4075)(-5400 4075);
FORCEPROP 2 LAST SIG_NAME TP_CPU1_TEST47_CCD0
J 0
(-6285 4085);
DISPLAY 0.489362 (-6285 4085);
FORCEPROP 2 LASTPROP $XRERR UNIQUE?
J 0
(-6765 4075);
DISPLAY 0.638298 (-6765 4075);
PAINT MONO (-6765 4075);
DISPLAY INVISIBLE (-6765 4075);
WIRE 16 -1 (-5400 2225)(-6400 2225);
FORCEPROP 2 LAST SIG_NAME VSENSE_PVDDCR_CPU0_P1_DP
J 2
(-5570 2235);
DISPLAY 0.489362 (-5570 2235);
WIRE 16 -1 (-6400 2225)(-6975 2225);
WIRE 16 -1 (-6400 2225)(-6400 1950);
WIRE 16 -1 (-6150 1950)(-6150 2025);
WIRE 16 -1 (-5400 2025)(-6150 2025);
FORCEPROP 2 LAST SIG_NAME VSENSE_PVDDCR_SOC_P1_DP
J 2
(-5595 2035);
DISPLAY 0.489362 (-5595 2035);
WIRE 16 -1 (-6975 2025)(-6150 2025);
WIRE 16 -1 (-6150 2125)(-5400 2125);
FORCEPROP 2 LAST SIG_NAME TP_VSENSE_PVDD33_S5_P1
J 0
(-6135 2135);
DISPLAY 0.489362 (-6135 2135);
FORCEPROP 2 LASTPROP $XRERR UNIQUE?
J 0
(-6390 2125);
DISPLAY 0.638298 (-6390 2125);
PAINT MONO (-6390 2125);
DISPLAY INVISIBLE (-6390 2125);
WIRE 16 -1 (-5400 2075)(-6225 2075);
FORCEPROP 2 LAST SIG_NAME VSENSE_PVDD18_S5_P1_DP
J 2
(-5620 2085);
DISPLAY 0.489362 (-5620 2085);
WIRE 16 -1 (-6225 2075)(-6975 2075);
WIRE 16 -1 (-6225 2075)(-6225 1950);
WIRE 16 -1 (-5400 2175)(-6325 2175);
FORCEPROP 2 LAST SIG_NAME VSENSE_PVDD11_S3_P1_DP
J 2
(-5620 2185);
DISPLAY 0.489362 (-5620 2185);
WIRE 16 -1 (-6325 2175)(-6975 2175);
WIRE 16 -1 (-6325 2175)(-6325 1950);
WIRE 16 -1 (-5400 2325)(-6550 2325);
FORCEPROP 2 LAST SIG_NAME VSENSE_PVDDIO_P1_DP
J 0
(-6120 2335);
DISPLAY 0.489362 (-6120 2335);
WIRE 16 -1 (-6550 2325)(-6975 2325);
WIRE 16 -1 (-6550 2325)(-6550 1950);
WIRE 16 -1 (-5400 2425)(-6675 2425);
FORCEPROP 2 LAST SIG_NAME VSENSE_PVDD18_S5_P1_DN
J 2
(-5620 2435);
DISPLAY 0.489362 (-5620 2435);
WIRE 16 -1 (-6675 2425)(-6975 2425);
WIRE 16 -1 (-6675 2425)(-6675 1950);
WIRE 16 -1 (-5400 2475)(-6750 2475);
FORCEPROP 2 LAST SIG_NAME VSENSE_VSS_SENSE_C_P1
J 2
(-5645 2485);
DISPLAY 0.489362 (-5645 2485);
WIRE 16 -1 (-6750 2475)(-6975 2475);
WIRE 16 -1 (-6750 1950)(-6750 2475);
WIRE 16 -1 (-5400 2575)(-6900 2575);
FORCEPROP 2 LAST SIG_NAME VSENSE_VSS_SENSE_A_P1
J 2
(-5645 2585);
DISPLAY 0.489362 (-5645 2585);
WIRE 16 -1 (-6900 2575)(-6975 2575);
WIRE 16 -1 (-6900 2575)(-6900 1950);
WIRE 16 -1 (-6525 3475)(-5400 3475);
FORCEPROP 2 LAST SIG_NAME TP_CPU1_TEST50_IOD
J 0
(-6285 3485);
DISPLAY 0.489362 (-6285 3485);
FORCEPROP 2 LASTPROP $XRERR UNIQUE?
J 0
(-6765 3475);
DISPLAY 0.638298 (-6765 3475);
PAINT MONO (-6765 3475);
DISPLAY INVISIBLE (-6765 3475);
WIRE 16 -1 (-7800 3025)(-8650 3025);
FORCEPROP 2 LAST SIG_NAME CPU1_CORETYPE2
J 0
(-8300 3035);
DISPLAY 0.489362 (-8300 3035);
WIRE 16 -1 (-8650 3075)(-7800 3075);
FORCEPROP 2 LAST SIG_NAME CPU1_CORETYPE1
J 0
(-8300 3085);
DISPLAY 0.489362 (-8300 3085);
WIRE 16 -1 (-8650 3125)(-7800 3125);
FORCEPROP 2 LAST SIG_NAME CPU1_CORETYPE0
J 0
(-8300 3135);
DISPLAY 0.489362 (-8300 3135);
WIRE 16 -1 (-8650 3175)(-7800 3175);
FORCEPROP 2 LAST SIG_NAME CPU1_SP5R4
J 0
(-8300 3185);
DISPLAY 0.489362 (-8300 3185);
WIRE 16 -1 (-8650 3225)(-7800 3225);
FORCEPROP 2 LAST SIG_NAME CPU1_SP5R3
J 0
(-8300 3235);
DISPLAY 0.489362 (-8300 3235);
WIRE 16 -1 (-8650 3275)(-7800 3275);
FORCEPROP 2 LAST SIG_NAME CPU1_SP5R2
J 0
(-8300 3285);
DISPLAY 0.489362 (-8300 3285);
WIRE 16 -1 (-8625 4600)(-7950 4600);
FORCEPROP 2 LAST SIG_NAME CPU1_SA1
J 0
(-8335 4610);
DISPLAY 0.489362 (-8335 4610);
WIRE 16 -1 (-8625 4600)(-8625 4575);
WIRE 16 -1 (-8750 4650)(-7950 4650);
FORCEPROP 2 LAST SIG_NAME CPU1_SA0
J 0
(-8335 4660);
DISPLAY 0.489362 (-8335 4660);
WIRE 16 -1 (-8750 4725)(-8750 4650);
WIRE 16 -1 (-8750 4650)(-8750 4575);
WIRE 16 -1 (-6150 5475)(-5400 5475);
FORCEPROP 2 LAST SIG_NAME SVID_PVDDCR_CPU1_P1_SVTO
J 0
(-6125 5485);
DISPLAY 0.489362 (-6125 5485);
WIRE 16 -1 (-6150 5925)(-5400 5925);
FORCEPROP 2 LAST SIG_NAME FM_P1_PCC0_N
J 0
(-6110 5935);
DISPLAY 0.489362 (-6110 5935);
WIRE 16 -1 (-6800 4825)(-6200 4825);
FORCEPROP 2 LAST SIG_NAME JTAG_CPU1_TDO
J 0
(-6725 4835);
DISPLAY 0.489362 (-6725 4835);
WIRE 16 -1 (-6000 4825)(-5400 4825);
FORCEPROP 2 LAST SIG_NAME JTAG_CPU1_R_TDO
J 0
(-5935 4835);
DISPLAY 0.489362 (-5935 4835);
FORCEPROP 2 LASTPROP $XRERR UNIQUE?
J 0
(-6175 4835);
DISPLAY 0.638298 (-6175 4835);
PAINT MONO (-6175 4835);
DISPLAY INVISIBLE (-6175 4835);
WIRE 16 -1 (-6675 5725)(-5400 5725);
FORCEPROP 2 LAST SIG_NAME SVID_PVDDCR_CPU0_P1_SVD
J 0
(-6125 5735);
DISPLAY 0.489362 (-6125 5735);
FORCEPROP 2 LASTPROP $XRERR UNIQUE?
J 0
(-6365 5735);
DISPLAY 0.638298 (-6365 5735);
PAINT MONO (-6365 5735);
DISPLAY INVISIBLE (-6365 5735);
WIRE 16 -1 (-7825 5725)(-6875 5725);
FORCEPROP 2 LAST SIG_NAME SVID_PVDDCR_CPU0_P1_SVD_R
J 0
(-7600 5735);
DISPLAY 0.489362 (-7600 5735);
WIRE 16 -1 (-6675 5775)(-5400 5775);
FORCEPROP 2 LAST SIG_NAME SVID_PVDDCR_CPU0_P1_SVC
J 0
(-6125 5785);
DISPLAY 0.489362 (-6125 5785);
FORCEPROP 2 LASTPROP $XRERR UNIQUE?
J 0
(-6365 5785);
DISPLAY 0.638298 (-6365 5785);
PAINT MONO (-6365 5785);
DISPLAY INVISIBLE (-6365 5785);
WIRE 16 -1 (-6875 5775)(-7825 5775);
FORCEPROP 2 LAST SIG_NAME SVID_PVDDCR_CPU0_P1_SVC_R
J 0
(-7600 5785);
DISPLAY 0.489362 (-7600 5785);
WIRE 16 -1 (-6675 5525)(-5400 5525);
FORCEPROP 2 LAST SIG_NAME SVID_PVDDCR_CPU1_P1_SVD
J 0
(-6125 5535);
DISPLAY 0.489362 (-6125 5535);
FORCEPROP 2 LASTPROP $XRERR UNIQUE?
J 0
(-6365 5535);
DISPLAY 0.638298 (-6365 5535);
PAINT MONO (-6365 5535);
DISPLAY INVISIBLE (-6365 5535);
WIRE 16 -1 (-7825 5525)(-6875 5525);
FORCEPROP 2 LAST SIG_NAME SVID_PVDDCR_CPU1_P1_SVD_R
J 0
(-7600 5535);
DISPLAY 0.489362 (-7600 5535);
WIRE 16 -1 (-6675 5575)(-5400 5575);
FORCEPROP 2 LAST SIG_NAME SVID_PVDDCR_CPU1_P1_SVC
J 0
(-6125 5585);
DISPLAY 0.489362 (-6125 5585);
FORCEPROP 2 LASTPROP $XRERR UNIQUE?
J 0
(-6365 5585);
DISPLAY 0.638298 (-6365 5585);
PAINT MONO (-6365 5585);
DISPLAY INVISIBLE (-6365 5585);
WIRE 16 -1 (-6875 5575)(-7825 5575);
FORCEPROP 2 LAST SIG_NAME SVID_PVDDCR_CPU1_P1_SVC_R
J 0
(-7600 5585);
DISPLAY 0.489362 (-7600 5585);
WIRE 16 -1 (-3000 4775)(-2425 4775);
FORCEPROP 2 LAST SIG_NAME CPU1_XTRIG_L5
J 0
(-2785 4785);
DISPLAY 0.489362 (-2785 4785);
WIRE 16 -1 (-3000 4825)(-2425 4825);
FORCEPROP 2 LAST SIG_NAME CPU1_XTRIG_L4
J 0
(-2785 4835);
DISPLAY 0.489362 (-2785 4835);
WIRE 16 -1 (-3900 4825)(-3200 4825);
FORCEPROP 2 LAST SIG_NAME CPU1_XTRIG_R2_L4
J 0
(-3685 4835);
DISPLAY 0.489362 (-3685 4835);
FORCEPROP 2 LASTPROP $XRERR UNIQUE?
J 0
(-3925 4835);
DISPLAY 0.638298 (-3925 4835);
PAINT MONO (-3925 4835);
DISPLAY INVISIBLE (-3925 4835);
WIRE 16 -1 (-3000 4675)(-2425 4675);
FORCEPROP 2 LAST SIG_NAME CPU1_XTRIG_L7
J 0
(-2785 4685);
DISPLAY 0.489362 (-2785 4685);
WIRE 16 -1 (-3000 4725)(-2425 4725);
FORCEPROP 2 LAST SIG_NAME CPU1_XTRIG_L6
J 0
(-2785 4735);
DISPLAY 0.489362 (-2785 4735);
WIRE 16 -1 (-3900 4725)(-3200 4725);
FORCEPROP 2 LAST SIG_NAME CPU1_XTRIG_R2_L6
J 0
(-3685 4735);
DISPLAY 0.489362 (-3685 4735);
FORCEPROP 2 LASTPROP $XRERR UNIQUE?
J 0
(-3925 4735);
DISPLAY 0.638298 (-3925 4735);
PAINT MONO (-3925 4735);
DISPLAY INVISIBLE (-3925 4735);
WIRE 16 -1 (-1525 3550)(-1975 3550);
FORCEPROP 2 LAST SIG_NAME CPU1_XTRIG_L6
J 0
(-1885 3560);
DISPLAY 0.489362 (-1885 3560);
WIRE 16 -1 (-8850 1075)(-7950 1075);
FORCEPROP 2 LAST SIG_NAME JTAG_CPU1_TDI
J 0
(-8785 1085);
DISPLAY 0.489362 (-8785 1085);
WIRE 16 -1 (-7950 1225)(-7950 1075);
WIRE 16 -1 (-7950 725)(-7950 1075);
WIRE 16 -1 (-8850 1125)(-8275 1125);
FORCEPROP 2 LAST SIG_NAME JTAG_CPU1_TDO
J 0
(-8785 1135);
DISPLAY 0.489362 (-8785 1135);
WIRE 16 -1 (-8275 1225)(-8275 1125);
WIRE 16 -1 (-8275 725)(-8275 1125);
WIRE 16 -1 (-8850 875)(-6725 875);
FORCEPROP 2 LAST SIG_NAME JTAG_CPU1_DBREQ_N
J 0
(-8785 885);
DISPLAY 0.489362 (-8785 885);
WIRE 16 -1 (-6725 875)(-6725 1225);
WIRE 16 -1 (-6725 725)(-6725 875);
WIRE 16 -1 (-8850 925)(-7000 925);
FORCEPROP 2 LAST SIG_NAME JTAG_CPU1_TMS
J 0
(-8785 935);
DISPLAY 0.489362 (-8785 935);
WIRE 16 -1 (-7000 1225)(-7000 925);
WIRE 16 -1 (-7000 725)(-7000 925);
WIRE 16 -1 (-8850 975)(-7300 975);
FORCEPROP 2 LAST SIG_NAME JTAG_CPU1_TCK
J 0
(-8785 985);
DISPLAY 0.489362 (-8785 985);
WIRE 16 -1 (-7300 1225)(-7300 975);
WIRE 16 -1 (-7300 725)(-7300 975);
WIRE 16 -1 (-8850 1025)(-7625 1025);
FORCEPROP 2 LAST SIG_NAME JTAG_CPU1_TRST_N
J 0
(-8785 1035);
DISPLAY 0.489362 (-8785 1035);
WIRE 16 -1 (-7625 1225)(-7625 1025);
WIRE 16 -1 (-7625 725)(-7625 1025);
WIRE 16 -1 (-3900 5125)(-3200 5125);
FORCEPROP 2 LAST SIG_NAME APML_CPU1_ALERT_N
J 0
(-3700 5135);
DISPLAY 0.489362 (-3700 5135);
FORCEPROP 2 LASTPROP $XR0 54 
J 0
(-3795 5135);
DISPLAY 0.638298 (-3795 5135);
PAINT MONO (-3795 5135);
WIRE 16 -1 (-3000 4975)(-2425 4975);
FORCEPROP 2 LAST SIG_NAME CPU1_THERMTRIP_R_N
J 0
(-2875 4985);
DISPLAY 0.489362 (-2875 4985);
WIRE 16 -1 (-3900 4975)(-3200 4975);
FORCEPROP 2 LAST SIG_NAME CPU1_THERMTRIP_N
J 0
(-3700 4985);
DISPLAY 0.489362 (-3700 4985);
FORCEPROP 2 LASTPROP $XR0 54 
J 0
(-3795 4985);
DISPLAY 0.638298 (-3795 4985);
PAINT MONO (-3795 4985);
WIRE 16 -1 (-1525 3500)(-1975 3500);
FORCEPROP 2 LAST SIG_NAME CPU1_XTRIG_L7
J 0
(-1885 3510);
DISPLAY 0.489362 (-1885 3510);
WIRE 16 -1 (-1525 3600)(-1975 3600);
FORCEPROP 2 LAST SIG_NAME CPU1_XTRIG_L5
J 0
(-1885 3610);
DISPLAY 0.489362 (-1885 3610);
WIRE 16 -1 (-1525 3650)(-1975 3650);
FORCEPROP 2 LAST SIG_NAME CPU1_XTRIG_L4
J 0
(-1885 3660);
DISPLAY 0.489362 (-1885 3660);
WIRE 16 -1 (-775 3500)(-1325 3500);
FORCEPROP 2 LAST SIG_NAME CPU1_XTRIG_R1_L7
J 0
(-1185 3510);
DISPLAY 0.489362 (-1185 3510);
FORCEPROP 2 LASTPROP $XRERR UNIQUE?
J 0
(-1425 3510);
DISPLAY 0.638298 (-1425 3510);
PAINT MONO (-1425 3510);
DISPLAY INVISIBLE (-1425 3510);
WIRE 16 -1 (-775 3550)(-1325 3550);
FORCEPROP 2 LAST SIG_NAME CPU1_XTRIG_R1_L6
J 0
(-1185 3560);
DISPLAY 0.489362 (-1185 3560);
FORCEPROP 2 LASTPROP $XRERR UNIQUE?
J 0
(-1425 3560);
DISPLAY 0.638298 (-1425 3560);
PAINT MONO (-1425 3560);
DISPLAY INVISIBLE (-1425 3560);
WIRE 16 -1 (-775 3600)(-1325 3600);
FORCEPROP 2 LAST SIG_NAME CPU1_XTRIG_R1_L5
J 0
(-1185 3610);
DISPLAY 0.489362 (-1185 3610);
FORCEPROP 2 LASTPROP $XRERR UNIQUE?
J 0
(-1425 3610);
DISPLAY 0.638298 (-1425 3610);
PAINT MONO (-1425 3610);
DISPLAY INVISIBLE (-1425 3610);
WIRE 16 -1 (-775 3650)(-1325 3650);
FORCEPROP 2 LAST SIG_NAME CPU1_XTRIG_R1_L4
J 0
(-1185 3660);
DISPLAY 0.489362 (-1185 3660);
FORCEPROP 2 LASTPROP $XRERR UNIQUE?
J 0
(-1425 3660);
DISPLAY 0.638298 (-1425 3660);
PAINT MONO (-1425 3660);
DISPLAY INVISIBLE (-1425 3660);
WIRE 16 -1 (-1925 2450)(-1300 2450);
FORCEPROP 2 LAST SIG_NAME CPU1_BP3
J 0
(-1710 2460);
DISPLAY 0.489362 (-1710 2460);
WIRE 16 -1 (-1925 2500)(-1300 2500);
FORCEPROP 2 LAST SIG_NAME CPU1_BP2
J 0
(-1710 2510);
DISPLAY 0.489362 (-1710 2510);
WIRE 16 -1 (-1925 2550)(-1300 2550);
FORCEPROP 2 LAST SIG_NAME CPU1_BP1
J 0
(-1710 2560);
DISPLAY 0.489362 (-1710 2560);
WIRE 16 -1 (-1925 2600)(-1300 2600);
FORCEPROP 2 LAST SIG_NAME CPU1_BP0
J 0
(-1710 2610);
DISPLAY 0.489362 (-1710 2610);
DOT 1 (-9050 3125);
DOT 1 (-8750 4650);
DOT 1 (-9050 3075);
DOT 1 (-6675 2425);
DOT 1 (-6225 2075);
DOT 1 (-6325 2175);
DOT 1 (-6400 2225);
DOT 1 (-6475 2275);
DOT 1 (-6550 2325);
DOT 1 (-6750 2475);
DOT 1 (-6825 2525);
DOT 1 (-6150 2025);
DOT 1 (-8275 1125);
DOT 1 (-8275 1500);
DOT 1 (-7950 1075);
DOT 1 (-7625 1025);
DOT 1 (-7300 975);
DOT 1 (-7000 925);
DOT 1 (-6725 875);
DOT 1 (-7950 1500);
DOT 1 (-7625 1500);
DOT 1 (-7300 1500);
DOT 1 (-7000 1500);
DOT 1 (-6900 2575);
DOT 1 (-9050 3275);
DOT 1 (-9050 3325);
DOT 1 (-9050 3175);
DOT 1 (-9050 3225);
DOT 1 (-150 6075);
DOT 1 (-150 5975);
DOT 1 (-150 5675);
DOT 1 (-150 5725);
DOT 1 (-150 5625);
DOT 1 (-150 5775);
DOT 1 (-150 3600);
DOT 1 (-150 3550);
DOT 1 (-150 3500);
DOT 1 (-675 2550);
DOT 1 (-675 2500);
DOT 1 (-675 2450);
DOT 1 (-150 6025);
DOT 1 (-150 5925);
DOT 1 (-150 5875);
DOT 1 (-150 5825);
QUIT
